FILE_TYPE = MACRO_DRAWING;
SET COLOR_WIRE YELLOW;
SET COLOR_PROP ORANGE;
SET COLOR_DOT WHITE;
SET COLOR_ARC YELLOW;
SET COLOR_BODY GREEN;
SET COLOR_NOTE PURPLE;
SET PROP_DISPLAY VALUE;
SET PAGE_NUMBER P384;
FORCEADD PT5161LRS..10
(-7800 4800);
FORCEPROP 1 LAST LOCATION U6010
J 0
(-8150 6425);
DISPLAY 0.723404 (-8150 6425);
PAINT GREEN (-8150 6425);
FORCEPROP 0 LAST $SEC 10
J 0
(-8150 6575);
DISPLAY 0.680851 (-8150 6575);
PAINT MONO (-8150 6575);
DISPLAY INVISIBLE (-8150 6575);
FORCEPROP 0 LAST CDS_SEC 10
J 0
(-8150 6575);
DISPLAY 0.680851 (-8150 6575);
DISPLAY INVISIBLE (-8150 6575);
FORCEPROP 0 LASTPIN (-7350 5950) $PN P10
J 0
(-7340 5960);
DISPLAY 0.680851 (-7340 5960);
PAINT MONO (-7340 5960);
FORCEPROP 0 LASTPIN (-7350 5600) $PN AA10
J 0
(-7340 5610);
DISPLAY 0.680851 (-7340 5610);
PAINT MONO (-7340 5610);
FORCEPROP 0 LASTPIN (-7350 5250) $PN AH10
J 0
(-7340 5260);
DISPLAY 0.680851 (-7340 5260);
PAINT MONO (-7340 5260);
FORCEPROP 0 LASTPIN (-7350 4900) $PN AR10
J 0
(-7340 4910);
DISPLAY 0.680851 (-7340 4910);
PAINT MONO (-7340 4910);
FORCEPROP 0 LASTPIN (-7350 4550) $PN BB10
J 0
(-7340 4560);
DISPLAY 0.680851 (-7340 4560);
PAINT MONO (-7340 4560);
FORCEPROP 0 LASTPIN (-7350 4200) $PN BJ10
J 0
(-7340 4210);
DISPLAY 0.680851 (-7340 4210);
PAINT MONO (-7340 4210);
FORCEPROP 0 LASTPIN (-7350 3850) $PN BT10
J 0
(-7340 3860);
DISPLAY 0.680851 (-7340 3860);
PAINT MONO (-7340 3860);
FORCEPROP 0 LASTPIN (-7350 3500) $PN CC10
J 0
(-7340 3510);
DISPLAY 0.680851 (-7340 3510);
PAINT MONO (-7340 3510);
FORCEPROP 0 LASTPIN (-7350 6050) $PN M7
J 0
(-7340 6060);
DISPLAY 0.680851 (-7340 6060);
PAINT MONO (-7340 6060);
FORCEPROP 0 LASTPIN (-7350 5700) $PN W7
J 0
(-7340 5710);
DISPLAY 0.680851 (-7340 5710);
PAINT MONO (-7340 5710);
FORCEPROP 0 LASTPIN (-7350 5350) $PN AF7
J 0
(-7340 5360);
DISPLAY 0.680851 (-7340 5360);
PAINT MONO (-7340 5360);
FORCEPROP 0 LASTPIN (-7350 5000) $PN AN7
J 0
(-7340 5010);
DISPLAY 0.680851 (-7340 5010);
PAINT MONO (-7340 5010);
FORCEPROP 0 LASTPIN (-7350 4650) $PN AY7
J 0
(-7340 4660);
DISPLAY 0.680851 (-7340 4660);
PAINT MONO (-7340 4660);
FORCEPROP 0 LASTPIN (-7350 4300) $PN BG7
J 0
(-7340 4310);
DISPLAY 0.680851 (-7340 4310);
PAINT MONO (-7340 4310);
FORCEPROP 0 LASTPIN (-7350 3950) $PN BP7
J 0
(-7340 3960);
DISPLAY 0.680851 (-7340 3960);
PAINT MONO (-7340 3960);
FORCEPROP 0 LASTPIN (-7350 3600) $PN CA7
J 0
(-7340 3610);
DISPLAY 0.680851 (-7340 3610);
PAINT MONO (-7340 3610);
FORCEPROP 2 LAST VALUE PT5161LRS
J 0
(-8150 6475);
DISPLAY 0.680851 (-8150 6475);
FORCEPROP 2 LAST PART_TYPE SMLF
J 0
(-8150 6525);
DISPLAY 0.680851 (-8150 6525);
FORCEPROP 1 LAST MATERIAL IC
J 0
(-8150 6275);
DISPLAY 0.723404 (-8150 6275);
PAINT GREEN (-8150 6275);
FORCEPROP 2 LAST CDS_LIB pure_quanta
J 0
(-7800 4800);
DISPLAY INVISIBLE (-7800 4800);
FORCEPROP 1 LAST CDS_LMAN_SYM_OUTLINE -350,1450,300,-1400
J 0
(-7800 4800);
DISPLAY 0.468085 (-7800 4800);
PAINT GREEN (-7800 4800);
DISPLAY INVISIBLE (-7800 4800);
FORCEPROP 1 LAST NEEDS_NO_SIZE TRUE
J 0
(-7800 4800);
DISPLAY 0.723404 (-7800 4800);
PAINT GREEN (-7800 4800);
DISPLAY INVISIBLE (-7800 4800);
FORCEPROP 1 LAST PATH I1
J 0
(-7800 4800);
DISPLAY 0.723404 (-7800 4800);
PAINT GREEN (-7800 4800);
DISPLAY INVISIBLE (-7800 4800);
FORCEPROP 1 LAST PART_NUMBER AJ051610U03
J 0
(-8150 6350);
DISPLAY 0.723404 (-8150 6350);
PAINT GREEN (-8150 6350);
DISPLAY INVISIBLE (-8150 6350);
FORCEADD TAP..1
(-7075 4650);
FORCEPROP 3 LASTPIN (-7125 4650) SIG_NAME P5E_CPU0_P0_TX_BUF_DP<11>
J 0
(-7115 4660);
DISPLAY 0.659574 (-7115 4660);
PAINT MONO (-7115 4660);
DISPLAY INVISIBLE (-7115 4660);
FORCEPROP 1 LASTPIN (-7125 4650) BN 11
J 0
(-7137 4658);
DISPLAY 0.680851 (-7137 4658);
PAINT GREEN (-7137 4658);
FORCEPROP 2 LAST CDS_LIB standard
J 0
(-7075 4650);
DISPLAY INVISIBLE (-7075 4650);
FORCEPROP 1 LAST BODY_TYPE PLUMBING
J 0
(-7075 4700);
DISPLAY 0.872340 (-7075 4700);
PAINT GREEN (-7075 4700);
DISPLAY INVISIBLE (-7075 4700);
FORCEPROP 1 LAST HDL_TAP TRUE
J 0
(-6750 4525);
DISPLAY 0.872340 (-6750 4525);
DISPLAY INVISIBLE (-6750 4525);
FORCEPROP 1 LAST PATH I10
J 0
(-7077 4650);
DISPLAY 0.872340 (-7077 4650);
PAINT GREEN (-7077 4650);
DISPLAY INVISIBLE (-7077 4650);
FORCEADD Q_CAP_DIFFBUS..2
R 2
(-7000 2275);
FORCEPROP 1 LAST LOCATION C6518
J 2
(-6725 2275);
DISPLAY 0.723404 (-6725 2275);
PAINT GREEN (-6725 2275);
FORCEPROP 2 LAST $SEC 1
J 2
(-6825 2350);
DISPLAY 0.680851 (-6825 2350);
PAINT MONO (-6825 2350);
DISPLAY INVISIBLE (-6825 2350);
FORCEPROP 2 LAST CDS_SEC 1
J 2
(-6825 2350);
DISPLAY 0.680851 (-6825 2350);
DISPLAY INVISIBLE (-6825 2350);
FORCEPROP 2 LASTPIN (-6925 2275) $PN 1
J 0
(-6915 2285);
DISPLAY 0.808511 (-6915 2285);
FORCEPROP 2 LASTPIN (-7075 2275) $PN 2
J 2
(-7085 2285);
DISPLAY 0.808511 (-7085 2285);
FORCEPROP 2 LAST VALUE DIFF BUS_0.22UF
J 2
(-7150 2275);
DISPLAY 0.553191 (-7150 2275);
FORCEPROP 1 LAST CDS_LMAN_SYM_OUTLINE -25,50,25,-50
J 2
(-7000 2275);
DISPLAY 0.468085 (-7000 2275);
PAINT GREEN (-7000 2275);
DISPLAY INVISIBLE (-7000 2275);
FORCEPROP 2 LAST CDS_LIB pure_quanta
J 2
(-7000 2275);
DISPLAY INVISIBLE (-7000 2275);
FORCEPROP 1 LAST PIN_NAMES_ROTATE TRUE
J 2
(-7000 2275);
DISPLAY 0.489362 (-7000 2275);
PAINT GREEN (-7000 2275);
DISPLAY INVISIBLE (-7000 2275);
FORCEPROP 2 LAST VOLTAGE 6.3V
J 2
(-7350 2325);
DISPLAY 0.553191 (-7350 2325);
DISPLAY INVISIBLE (-7350 2325);
FORCEPROP 1 LAST MATERIAL X6S
J 2
(-6991 2354);
DISPLAY 0.574468 (-6991 2354);
PAINT GREEN (-6991 2354);
DISPLAY INVISIBLE (-6991 2354);
FORCEPROP 2 LAST PACK_TYPE C0201
J 2
(-7175 2325);
DISPLAY 0.553191 (-7175 2325);
DISPLAY INVISIBLE (-7175 2325);
FORCEPROP 2 LAST TOLERANCE 20%
J 2
(-7075 2325);
DISPLAY 0.553191 (-7075 2325);
DISPLAY INVISIBLE (-7075 2325);
FORCEPROP 1 LAST PATH I100
J 2
(-7000 2275);
DISPLAY 0.723404 (-7000 2275);
DISPLAY INVISIBLE (-7000 2275);
FORCEPROP 1 LAST PART_NUMBER SP_CH4221MEE01
J 2
(-7116 2363);
DISPLAY 0.574468 (-7116 2363);
PAINT GREEN (-7116 2363);
DISPLAY INVISIBLE (-7116 2363);
FORCEPROP 1 LAST LOCATION C6518
J 0
(-6750 2350);
DISPLAY 1.021277 (-6750 2350);
DISPLAY INVISIBLE (-6750 2350);
FORCEADD Q_CAP_DIFFBUS..2
R 2
(-7000 2075);
FORCEPROP 1 LAST LOCATION C6520
J 2
(-6725 2075);
DISPLAY 0.723404 (-6725 2075);
PAINT GREEN (-6725 2075);
FORCEPROP 2 LAST $SEC 1
J 2
(-6825 2150);
DISPLAY 0.680851 (-6825 2150);
PAINT MONO (-6825 2150);
DISPLAY INVISIBLE (-6825 2150);
FORCEPROP 2 LAST CDS_SEC 1
J 2
(-6825 2150);
DISPLAY 0.680851 (-6825 2150);
DISPLAY INVISIBLE (-6825 2150);
FORCEPROP 2 LASTPIN (-6925 2075) $PN 1
J 0
(-6915 2085);
DISPLAY 0.808511 (-6915 2085);
FORCEPROP 2 LASTPIN (-7075 2075) $PN 2
J 2
(-7085 2085);
DISPLAY 0.808511 (-7085 2085);
FORCEPROP 2 LAST VALUE DIFF BUS_0.22UF
J 2
(-7150 2075);
DISPLAY 0.553191 (-7150 2075);
FORCEPROP 1 LAST CDS_LMAN_SYM_OUTLINE -25,50,25,-50
J 2
(-7000 2075);
DISPLAY 0.468085 (-7000 2075);
PAINT GREEN (-7000 2075);
DISPLAY INVISIBLE (-7000 2075);
FORCEPROP 2 LAST CDS_LIB pure_quanta
J 2
(-7000 2075);
DISPLAY INVISIBLE (-7000 2075);
FORCEPROP 1 LAST PIN_NAMES_ROTATE TRUE
J 2
(-7000 2075);
DISPLAY 0.489362 (-7000 2075);
PAINT GREEN (-7000 2075);
DISPLAY INVISIBLE (-7000 2075);
FORCEPROP 2 LAST VOLTAGE 6.3V
J 2
(-7350 2125);
DISPLAY 0.553191 (-7350 2125);
DISPLAY INVISIBLE (-7350 2125);
FORCEPROP 1 LAST MATERIAL X6S
J 2
(-6991 2154);
DISPLAY 0.574468 (-6991 2154);
PAINT GREEN (-6991 2154);
DISPLAY INVISIBLE (-6991 2154);
FORCEPROP 2 LAST PACK_TYPE C0201
J 2
(-7175 2125);
DISPLAY 0.553191 (-7175 2125);
DISPLAY INVISIBLE (-7175 2125);
FORCEPROP 2 LAST TOLERANCE 20%
J 2
(-7075 2125);
DISPLAY 0.553191 (-7075 2125);
DISPLAY INVISIBLE (-7075 2125);
FORCEPROP 1 LAST PATH I101
J 2
(-7000 2075);
DISPLAY 0.723404 (-7000 2075);
DISPLAY INVISIBLE (-7000 2075);
FORCEPROP 1 LAST PART_NUMBER SP_CH4221MEE01
J 2
(-7116 2163);
DISPLAY 0.574468 (-7116 2163);
PAINT GREEN (-7116 2163);
DISPLAY INVISIBLE (-7116 2163);
FORCEPROP 1 LAST LOCATION C6520
J 0
(-6750 2150);
DISPLAY 1.021277 (-6750 2150);
DISPLAY INVISIBLE (-6750 2150);
FORCEADD Q_CAP_DIFFBUS..2
R 2
(-7000 2125);
FORCEPROP 1 LAST LOCATION C6519
J 2
(-6725 2125);
DISPLAY 0.723404 (-6725 2125);
PAINT GREEN (-6725 2125);
FORCEPROP 2 LAST $SEC 1
J 2
(-6825 2200);
DISPLAY 0.680851 (-6825 2200);
PAINT MONO (-6825 2200);
DISPLAY INVISIBLE (-6825 2200);
FORCEPROP 2 LAST CDS_SEC 1
J 2
(-6825 2200);
DISPLAY 0.680851 (-6825 2200);
DISPLAY INVISIBLE (-6825 2200);
FORCEPROP 2 LASTPIN (-6925 2125) $PN 1
J 0
(-6915 2135);
DISPLAY 0.808511 (-6915 2135);
FORCEPROP 2 LASTPIN (-7075 2125) $PN 2
J 2
(-7085 2135);
DISPLAY 0.808511 (-7085 2135);
FORCEPROP 2 LAST VALUE DIFF BUS_0.22UF
J 2
(-7150 2125);
DISPLAY 0.553191 (-7150 2125);
FORCEPROP 1 LAST CDS_LMAN_SYM_OUTLINE -25,50,25,-50
J 2
(-7000 2125);
DISPLAY 0.468085 (-7000 2125);
PAINT GREEN (-7000 2125);
DISPLAY INVISIBLE (-7000 2125);
FORCEPROP 2 LAST CDS_LIB pure_quanta
J 2
(-7000 2125);
DISPLAY INVISIBLE (-7000 2125);
FORCEPROP 1 LAST PIN_NAMES_ROTATE TRUE
J 2
(-7000 2125);
DISPLAY 0.489362 (-7000 2125);
PAINT GREEN (-7000 2125);
DISPLAY INVISIBLE (-7000 2125);
FORCEPROP 2 LAST VOLTAGE 6.3V
J 2
(-7350 2175);
DISPLAY 0.553191 (-7350 2175);
DISPLAY INVISIBLE (-7350 2175);
FORCEPROP 1 LAST MATERIAL X6S
J 2
(-6991 2204);
DISPLAY 0.574468 (-6991 2204);
PAINT GREEN (-6991 2204);
DISPLAY INVISIBLE (-6991 2204);
FORCEPROP 2 LAST PACK_TYPE C0201
J 2
(-7175 2175);
DISPLAY 0.553191 (-7175 2175);
DISPLAY INVISIBLE (-7175 2175);
FORCEPROP 2 LAST TOLERANCE 20%
J 2
(-7075 2175);
DISPLAY 0.553191 (-7075 2175);
DISPLAY INVISIBLE (-7075 2175);
FORCEPROP 1 LAST PATH I102
J 2
(-7000 2125);
DISPLAY 0.723404 (-7000 2125);
DISPLAY INVISIBLE (-7000 2125);
FORCEPROP 1 LAST PART_NUMBER SP_CH4221MEE01
J 2
(-7116 2213);
DISPLAY 0.574468 (-7116 2213);
PAINT GREEN (-7116 2213);
DISPLAY INVISIBLE (-7116 2213);
FORCEPROP 1 LAST LOCATION C6519
J 0
(-6750 2200);
DISPLAY 1.021277 (-6750 2200);
DISPLAY INVISIBLE (-6750 2200);
FORCEADD TAP..1
R 2
(-7725 2325);
FORCEPROP 3 LASTPIN (-7675 2325) SIG_NAME P5E_CPU0_P0_TX_BUF_DP<8>
J 0
(-7665 2335);
DISPLAY 0.659574 (-7665 2335);
PAINT MONO (-7665 2335);
DISPLAY INVISIBLE (-7665 2335);
FORCEPROP 1 LASTPIN (-7675 2325) BN 8
J 2
(-7663 2333);
DISPLAY 0.680851 (-7663 2333);
PAINT GREEN (-7663 2333);
FORCEPROP 2 LAST CDS_LIB standard
J 0
(-7725 2325);
DISPLAY INVISIBLE (-7725 2325);
FORCEPROP 1 LAST BODY_TYPE PLUMBING
J 2
(-7725 2375);
DISPLAY 0.872340 (-7725 2375);
PAINT GREEN (-7725 2375);
DISPLAY INVISIBLE (-7725 2375);
FORCEPROP 1 LAST HDL_TAP TRUE
J 2
(-8050 2200);
DISPLAY 0.872340 (-8050 2200);
DISPLAY INVISIBLE (-8050 2200);
FORCEPROP 1 LAST PATH I103
J 2
(-7723 2325);
DISPLAY 0.872340 (-7723 2325);
PAINT GREEN (-7723 2325);
DISPLAY INVISIBLE (-7723 2325);
FORCEADD TAP..1
R 2
(-7725 2125);
FORCEPROP 3 LASTPIN (-7675 2125) SIG_NAME P5E_CPU0_P0_TX_BUF_DP<9>
J 0
(-7665 2135);
DISPLAY 0.659574 (-7665 2135);
PAINT MONO (-7665 2135);
DISPLAY INVISIBLE (-7665 2135);
FORCEPROP 1 LASTPIN (-7675 2125) BN 9
J 2
(-7663 2133);
DISPLAY 0.680851 (-7663 2133);
PAINT GREEN (-7663 2133);
FORCEPROP 2 LAST CDS_LIB standard
J 0
(-7725 2125);
DISPLAY INVISIBLE (-7725 2125);
FORCEPROP 1 LAST BODY_TYPE PLUMBING
J 2
(-7725 2175);
DISPLAY 0.872340 (-7725 2175);
PAINT GREEN (-7725 2175);
DISPLAY INVISIBLE (-7725 2175);
FORCEPROP 1 LAST HDL_TAP TRUE
J 2
(-8050 2000);
DISPLAY 0.872340 (-8050 2000);
DISPLAY INVISIBLE (-8050 2000);
FORCEPROP 1 LAST PATH I104
J 2
(-7723 2125);
DISPLAY 0.872340 (-7723 2125);
PAINT GREEN (-7723 2125);
DISPLAY INVISIBLE (-7723 2125);
FORCEADD TAP..1
R 2
(-7975 2275);
FORCEPROP 3 LASTPIN (-7925 2275) SIG_NAME P5E_CPU0_P0_TX_BUF_DN<8>
J 0
(-7915 2285);
DISPLAY 0.659574 (-7915 2285);
PAINT MONO (-7915 2285);
DISPLAY INVISIBLE (-7915 2285);
FORCEPROP 1 LASTPIN (-7925 2275) BN 8
J 2
(-7913 2283);
DISPLAY 0.680851 (-7913 2283);
PAINT GREEN (-7913 2283);
FORCEPROP 2 LAST CDS_LIB standard
J 0
(-7975 2275);
DISPLAY INVISIBLE (-7975 2275);
FORCEPROP 1 LAST BODY_TYPE PLUMBING
J 2
(-7975 2325);
DISPLAY 0.872340 (-7975 2325);
PAINT GREEN (-7975 2325);
DISPLAY INVISIBLE (-7975 2325);
FORCEPROP 1 LAST HDL_TAP TRUE
J 2
(-8300 2150);
DISPLAY 0.872340 (-8300 2150);
DISPLAY INVISIBLE (-8300 2150);
FORCEPROP 1 LAST PATH I105
J 2
(-7973 2275);
DISPLAY 0.872340 (-7973 2275);
PAINT GREEN (-7973 2275);
DISPLAY INVISIBLE (-7973 2275);
FORCEADD TAP..1
R 2
(-7975 2075);
FORCEPROP 3 LASTPIN (-7925 2075) SIG_NAME P5E_CPU0_P0_TX_BUF_DN<9>
J 0
(-7915 2085);
DISPLAY 0.659574 (-7915 2085);
PAINT MONO (-7915 2085);
DISPLAY INVISIBLE (-7915 2085);
FORCEPROP 1 LASTPIN (-7925 2075) BN 9
J 2
(-7913 2083);
DISPLAY 0.680851 (-7913 2083);
PAINT GREEN (-7913 2083);
FORCEPROP 2 LAST CDS_LIB standard
J 0
(-7975 2075);
DISPLAY INVISIBLE (-7975 2075);
FORCEPROP 1 LAST BODY_TYPE PLUMBING
J 2
(-7975 2125);
DISPLAY 0.872340 (-7975 2125);
PAINT GREEN (-7975 2125);
DISPLAY INVISIBLE (-7975 2125);
FORCEPROP 1 LAST HDL_TAP TRUE
J 2
(-8300 1950);
DISPLAY 0.872340 (-8300 1950);
DISPLAY INVISIBLE (-8300 1950);
FORCEPROP 1 LAST PATH I106
J 2
(-7973 2075);
DISPLAY 0.872340 (-7973 2075);
PAINT GREEN (-7973 2075);
DISPLAY INVISIBLE (-7973 2075);
FORCEADD TAP..1
(-6250 1875);
FORCEPROP 3 LASTPIN (-6300 1875) SIG_NAME P5E_CPU0_P0_TX_BUF_C_DN<10>
J 0
(-6290 1885);
DISPLAY 0.659574 (-6290 1885);
PAINT MONO (-6290 1885);
DISPLAY INVISIBLE (-6290 1885);
FORCEPROP 1 LASTPIN (-6300 1875) BN 10
J 0
(-6312 1883);
DISPLAY 0.680851 (-6312 1883);
PAINT GREEN (-6312 1883);
FORCEPROP 2 LAST CDS_LIB standard
J 0
(-6250 1875);
DISPLAY INVISIBLE (-6250 1875);
FORCEPROP 1 LAST BODY_TYPE PLUMBING
J 0
(-6250 1925);
DISPLAY 0.872340 (-6250 1925);
PAINT GREEN (-6250 1925);
DISPLAY INVISIBLE (-6250 1925);
FORCEPROP 1 LAST HDL_TAP TRUE
J 0
(-5925 1750);
DISPLAY 0.872340 (-5925 1750);
DISPLAY INVISIBLE (-5925 1750);
FORCEPROP 1 LAST PATH I107
J 0
(-6252 1875);
DISPLAY 0.872340 (-6252 1875);
PAINT GREEN (-6252 1875);
DISPLAY INVISIBLE (-6252 1875);
FORCEADD TAP..1
(-6250 1675);
FORCEPROP 3 LASTPIN (-6300 1675) SIG_NAME P5E_CPU0_P0_TX_BUF_C_DN<11>
J 0
(-6290 1685);
DISPLAY 0.659574 (-6290 1685);
PAINT MONO (-6290 1685);
DISPLAY INVISIBLE (-6290 1685);
FORCEPROP 1 LASTPIN (-6300 1675) BN 11
J 0
(-6312 1683);
DISPLAY 0.680851 (-6312 1683);
PAINT GREEN (-6312 1683);
FORCEPROP 2 LAST CDS_LIB standard
J 0
(-6250 1675);
DISPLAY INVISIBLE (-6250 1675);
FORCEPROP 1 LAST BODY_TYPE PLUMBING
J 0
(-6250 1725);
DISPLAY 0.872340 (-6250 1725);
PAINT GREEN (-6250 1725);
DISPLAY INVISIBLE (-6250 1725);
FORCEPROP 1 LAST HDL_TAP TRUE
J 0
(-5925 1550);
DISPLAY 0.872340 (-5925 1550);
DISPLAY INVISIBLE (-5925 1550);
FORCEPROP 1 LAST PATH I108
J 0
(-6252 1675);
DISPLAY 0.872340 (-6252 1675);
PAINT GREEN (-6252 1675);
DISPLAY INVISIBLE (-6252 1675);
FORCEADD TAP..1
(-6250 1475);
FORCEPROP 3 LASTPIN (-6300 1475) SIG_NAME P5E_CPU0_P0_TX_BUF_C_DN<12>
J 0
(-6290 1485);
DISPLAY 0.659574 (-6290 1485);
PAINT MONO (-6290 1485);
DISPLAY INVISIBLE (-6290 1485);
FORCEPROP 1 LASTPIN (-6300 1475) BN 12
J 0
(-6312 1483);
DISPLAY 0.680851 (-6312 1483);
PAINT GREEN (-6312 1483);
FORCEPROP 2 LAST CDS_LIB standard
J 0
(-6250 1475);
DISPLAY INVISIBLE (-6250 1475);
FORCEPROP 1 LAST BODY_TYPE PLUMBING
J 0
(-6250 1525);
DISPLAY 0.872340 (-6250 1525);
PAINT GREEN (-6250 1525);
DISPLAY INVISIBLE (-6250 1525);
FORCEPROP 1 LAST HDL_TAP TRUE
J 0
(-5925 1350);
DISPLAY 0.872340 (-5925 1350);
DISPLAY INVISIBLE (-5925 1350);
FORCEPROP 1 LAST PATH I109
J 0
(-6252 1475);
DISPLAY 0.872340 (-6252 1475);
PAINT GREEN (-6252 1475);
DISPLAY INVISIBLE (-6252 1475);
FORCEADD TAP..1
(-6875 4900);
FORCEPROP 3 LASTPIN (-6925 4900) SIG_NAME P5E_CPU0_P0_TX_BUF_DN<12>
J 0
(-6915 4910);
DISPLAY 0.659574 (-6915 4910);
PAINT MONO (-6915 4910);
DISPLAY INVISIBLE (-6915 4910);
FORCEPROP 1 LASTPIN (-6925 4900) BN 12
J 0
(-6937 4908);
DISPLAY 0.680851 (-6937 4908);
PAINT GREEN (-6937 4908);
FORCEPROP 2 LAST CDS_LIB standard
J 0
(-6875 4900);
DISPLAY INVISIBLE (-6875 4900);
FORCEPROP 1 LAST BODY_TYPE PLUMBING
J 0
(-6875 4950);
DISPLAY 0.872340 (-6875 4950);
PAINT GREEN (-6875 4950);
DISPLAY INVISIBLE (-6875 4950);
FORCEPROP 1 LAST HDL_TAP TRUE
J 0
(-6550 4775);
DISPLAY 0.872340 (-6550 4775);
DISPLAY INVISIBLE (-6550 4775);
FORCEPROP 1 LAST PATH I11
J 0
(-6877 4900);
DISPLAY 0.872340 (-6877 4900);
PAINT GREEN (-6877 4900);
DISPLAY INVISIBLE (-6877 4900);
FORCEADD TAP..1
(-6450 1525);
FORCEPROP 3 LASTPIN (-6500 1525) SIG_NAME P5E_CPU0_P0_TX_BUF_C_DP<12>
J 0
(-6490 1535);
DISPLAY 0.659574 (-6490 1535);
PAINT MONO (-6490 1535);
DISPLAY INVISIBLE (-6490 1535);
FORCEPROP 1 LASTPIN (-6500 1525) BN 12
J 0
(-6512 1533);
DISPLAY 0.680851 (-6512 1533);
PAINT GREEN (-6512 1533);
FORCEPROP 2 LAST CDS_LIB standard
J 0
(-6450 1525);
DISPLAY INVISIBLE (-6450 1525);
FORCEPROP 1 LAST BODY_TYPE PLUMBING
J 0
(-6450 1575);
DISPLAY 0.872340 (-6450 1575);
PAINT GREEN (-6450 1575);
DISPLAY INVISIBLE (-6450 1575);
FORCEPROP 1 LAST HDL_TAP TRUE
J 0
(-6125 1400);
DISPLAY 0.872340 (-6125 1400);
DISPLAY INVISIBLE (-6125 1400);
FORCEPROP 1 LAST PATH I110
J 0
(-6452 1525);
DISPLAY 0.872340 (-6452 1525);
PAINT GREEN (-6452 1525);
DISPLAY INVISIBLE (-6452 1525);
FORCEADD TAP..1
(-6450 1725);
FORCEPROP 3 LASTPIN (-6500 1725) SIG_NAME P5E_CPU0_P0_TX_BUF_C_DP<11>
J 0
(-6490 1735);
DISPLAY 0.659574 (-6490 1735);
PAINT MONO (-6490 1735);
DISPLAY INVISIBLE (-6490 1735);
FORCEPROP 1 LASTPIN (-6500 1725) BN 11
J 0
(-6512 1733);
DISPLAY 0.680851 (-6512 1733);
PAINT GREEN (-6512 1733);
FORCEPROP 2 LAST CDS_LIB standard
J 0
(-6450 1725);
DISPLAY INVISIBLE (-6450 1725);
FORCEPROP 1 LAST BODY_TYPE PLUMBING
J 0
(-6450 1775);
DISPLAY 0.872340 (-6450 1775);
PAINT GREEN (-6450 1775);
DISPLAY INVISIBLE (-6450 1775);
FORCEPROP 1 LAST HDL_TAP TRUE
J 0
(-6125 1600);
DISPLAY 0.872340 (-6125 1600);
DISPLAY INVISIBLE (-6125 1600);
FORCEPROP 1 LAST PATH I111
J 0
(-6452 1725);
DISPLAY 0.872340 (-6452 1725);
PAINT GREEN (-6452 1725);
DISPLAY INVISIBLE (-6452 1725);
FORCEADD TAP..1
(-6450 1925);
FORCEPROP 3 LASTPIN (-6500 1925) SIG_NAME P5E_CPU0_P0_TX_BUF_C_DP<10>
J 0
(-6490 1935);
DISPLAY 0.659574 (-6490 1935);
PAINT MONO (-6490 1935);
DISPLAY INVISIBLE (-6490 1935);
FORCEPROP 1 LASTPIN (-6500 1925) BN 10
J 0
(-6512 1933);
DISPLAY 0.680851 (-6512 1933);
PAINT GREEN (-6512 1933);
FORCEPROP 2 LAST CDS_LIB standard
J 0
(-6450 1925);
DISPLAY INVISIBLE (-6450 1925);
FORCEPROP 1 LAST BODY_TYPE PLUMBING
J 0
(-6450 1975);
DISPLAY 0.872340 (-6450 1975);
PAINT GREEN (-6450 1975);
DISPLAY INVISIBLE (-6450 1975);
FORCEPROP 1 LAST HDL_TAP TRUE
J 0
(-6125 1800);
DISPLAY 0.872340 (-6125 1800);
DISPLAY INVISIBLE (-6125 1800);
FORCEPROP 1 LAST PATH I112
J 0
(-6452 1925);
DISPLAY 0.872340 (-6452 1925);
PAINT GREEN (-6452 1925);
DISPLAY INVISIBLE (-6452 1925);
FORCEADD TAP..1
(-6250 1275);
FORCEPROP 3 LASTPIN (-6300 1275) SIG_NAME P5E_CPU0_P0_TX_BUF_C_DN<13>
J 0
(-6290 1285);
DISPLAY 0.659574 (-6290 1285);
PAINT MONO (-6290 1285);
DISPLAY INVISIBLE (-6290 1285);
FORCEPROP 1 LASTPIN (-6300 1275) BN 13
J 0
(-6312 1283);
DISPLAY 0.680851 (-6312 1283);
PAINT GREEN (-6312 1283);
FORCEPROP 2 LAST CDS_LIB standard
J 0
(-6250 1275);
DISPLAY INVISIBLE (-6250 1275);
FORCEPROP 1 LAST BODY_TYPE PLUMBING
J 0
(-6250 1325);
DISPLAY 0.872340 (-6250 1325);
PAINT GREEN (-6250 1325);
DISPLAY INVISIBLE (-6250 1325);
FORCEPROP 1 LAST HDL_TAP TRUE
J 0
(-5925 1150);
DISPLAY 0.872340 (-5925 1150);
DISPLAY INVISIBLE (-5925 1150);
FORCEPROP 1 LAST PATH I113
J 0
(-6252 1275);
DISPLAY 0.872340 (-6252 1275);
PAINT GREEN (-6252 1275);
DISPLAY INVISIBLE (-6252 1275);
FORCEADD TAP..1
(-6250 1075);
FORCEPROP 3 LASTPIN (-6300 1075) SIG_NAME P5E_CPU0_P0_TX_BUF_C_DN<14>
J 0
(-6290 1085);
DISPLAY 0.659574 (-6290 1085);
PAINT MONO (-6290 1085);
DISPLAY INVISIBLE (-6290 1085);
FORCEPROP 1 LASTPIN (-6300 1075) BN 14
J 0
(-6312 1083);
DISPLAY 0.680851 (-6312 1083);
PAINT GREEN (-6312 1083);
FORCEPROP 2 LAST CDS_LIB standard
J 0
(-6250 1075);
DISPLAY INVISIBLE (-6250 1075);
FORCEPROP 1 LAST BODY_TYPE PLUMBING
J 0
(-6250 1125);
DISPLAY 0.872340 (-6250 1125);
PAINT GREEN (-6250 1125);
DISPLAY INVISIBLE (-6250 1125);
FORCEPROP 1 LAST HDL_TAP TRUE
J 0
(-5925 950);
DISPLAY 0.872340 (-5925 950);
DISPLAY INVISIBLE (-5925 950);
FORCEPROP 1 LAST PATH I114
J 0
(-6252 1075);
DISPLAY 0.872340 (-6252 1075);
PAINT GREEN (-6252 1075);
DISPLAY INVISIBLE (-6252 1075);
FORCEADD TAP..1
(-6450 925);
FORCEPROP 3 LASTPIN (-6500 925) SIG_NAME P5E_CPU0_P0_TX_BUF_C_DP<15>
J 0
(-6490 935);
DISPLAY 0.659574 (-6490 935);
PAINT MONO (-6490 935);
DISPLAY INVISIBLE (-6490 935);
FORCEPROP 1 LASTPIN (-6500 925) BN 15
J 0
(-6512 933);
DISPLAY 0.680851 (-6512 933);
PAINT GREEN (-6512 933);
FORCEPROP 2 LAST CDS_LIB standard
J 0
(-6450 925);
DISPLAY INVISIBLE (-6450 925);
FORCEPROP 1 LAST BODY_TYPE PLUMBING
J 0
(-6450 975);
DISPLAY 0.872340 (-6450 975);
PAINT GREEN (-6450 975);
DISPLAY INVISIBLE (-6450 975);
FORCEPROP 1 LAST HDL_TAP TRUE
J 0
(-6125 800);
DISPLAY 0.872340 (-6125 800);
DISPLAY INVISIBLE (-6125 800);
FORCEPROP 1 LAST PATH I115
J 0
(-6452 925);
DISPLAY 0.872340 (-6452 925);
PAINT GREEN (-6452 925);
DISPLAY INVISIBLE (-6452 925);
FORCEADD TAP..1
(-6450 1125);
FORCEPROP 3 LASTPIN (-6500 1125) SIG_NAME P5E_CPU0_P0_TX_BUF_C_DP<14>
J 0
(-6490 1135);
DISPLAY 0.659574 (-6490 1135);
PAINT MONO (-6490 1135);
DISPLAY INVISIBLE (-6490 1135);
FORCEPROP 1 LASTPIN (-6500 1125) BN 14
J 0
(-6512 1133);
DISPLAY 0.680851 (-6512 1133);
PAINT GREEN (-6512 1133);
FORCEPROP 2 LAST CDS_LIB standard
J 0
(-6450 1125);
DISPLAY INVISIBLE (-6450 1125);
FORCEPROP 1 LAST BODY_TYPE PLUMBING
J 0
(-6450 1175);
DISPLAY 0.872340 (-6450 1175);
PAINT GREEN (-6450 1175);
DISPLAY INVISIBLE (-6450 1175);
FORCEPROP 1 LAST HDL_TAP TRUE
J 0
(-6125 1000);
DISPLAY 0.872340 (-6125 1000);
DISPLAY INVISIBLE (-6125 1000);
FORCEPROP 1 LAST PATH I116
J 0
(-6452 1125);
DISPLAY 0.872340 (-6452 1125);
PAINT GREEN (-6452 1125);
DISPLAY INVISIBLE (-6452 1125);
FORCEADD TAP..1
(-6450 1325);
FORCEPROP 3 LASTPIN (-6500 1325) SIG_NAME P5E_CPU0_P0_TX_BUF_C_DP<13>
J 0
(-6490 1335);
DISPLAY 0.659574 (-6490 1335);
PAINT MONO (-6490 1335);
DISPLAY INVISIBLE (-6490 1335);
FORCEPROP 1 LASTPIN (-6500 1325) BN 13
J 0
(-6512 1333);
DISPLAY 0.680851 (-6512 1333);
PAINT GREEN (-6512 1333);
FORCEPROP 2 LAST CDS_LIB standard
J 0
(-6450 1325);
DISPLAY INVISIBLE (-6450 1325);
FORCEPROP 1 LAST BODY_TYPE PLUMBING
J 0
(-6450 1375);
DISPLAY 0.872340 (-6450 1375);
PAINT GREEN (-6450 1375);
DISPLAY INVISIBLE (-6450 1375);
FORCEPROP 1 LAST HDL_TAP TRUE
J 0
(-6125 1200);
DISPLAY 0.872340 (-6125 1200);
DISPLAY INVISIBLE (-6125 1200);
FORCEPROP 1 LAST PATH I117
J 0
(-6452 1325);
DISPLAY 0.872340 (-6452 1325);
PAINT GREEN (-6452 1325);
DISPLAY INVISIBLE (-6452 1325);
FORCEADD Q_CAP_DIFFBUS..2
R 2
(-7000 1875);
FORCEPROP 1 LAST LOCATION C6522
J 2
(-6725 1875);
DISPLAY 0.723404 (-6725 1875);
PAINT GREEN (-6725 1875);
FORCEPROP 2 LAST $SEC 1
J 2
(-6825 1950);
DISPLAY 0.680851 (-6825 1950);
PAINT MONO (-6825 1950);
DISPLAY INVISIBLE (-6825 1950);
FORCEPROP 2 LAST CDS_SEC 1
J 2
(-6825 1950);
DISPLAY 0.680851 (-6825 1950);
DISPLAY INVISIBLE (-6825 1950);
FORCEPROP 2 LASTPIN (-6925 1875) $PN 1
J 0
(-6915 1885);
DISPLAY 0.808511 (-6915 1885);
FORCEPROP 2 LASTPIN (-7075 1875) $PN 2
J 2
(-7085 1885);
DISPLAY 0.808511 (-7085 1885);
FORCEPROP 2 LAST VALUE DIFF BUS_0.22UF
J 2
(-7150 1875);
DISPLAY 0.553191 (-7150 1875);
FORCEPROP 1 LAST CDS_LMAN_SYM_OUTLINE -25,50,25,-50
J 2
(-7000 1875);
DISPLAY 0.468085 (-7000 1875);
PAINT GREEN (-7000 1875);
DISPLAY INVISIBLE (-7000 1875);
FORCEPROP 2 LAST CDS_LIB pure_quanta
J 2
(-7000 1875);
DISPLAY INVISIBLE (-7000 1875);
FORCEPROP 1 LAST PIN_NAMES_ROTATE TRUE
J 2
(-7000 1875);
DISPLAY 0.489362 (-7000 1875);
PAINT GREEN (-7000 1875);
DISPLAY INVISIBLE (-7000 1875);
FORCEPROP 2 LAST VOLTAGE 6.3V
J 2
(-7350 1925);
DISPLAY 0.553191 (-7350 1925);
DISPLAY INVISIBLE (-7350 1925);
FORCEPROP 1 LAST MATERIAL X6S
J 2
(-6991 1954);
DISPLAY 0.574468 (-6991 1954);
PAINT GREEN (-6991 1954);
DISPLAY INVISIBLE (-6991 1954);
FORCEPROP 2 LAST PACK_TYPE C0201
J 2
(-7175 1925);
DISPLAY 0.553191 (-7175 1925);
DISPLAY INVISIBLE (-7175 1925);
FORCEPROP 2 LAST TOLERANCE 20%
J 2
(-7075 1925);
DISPLAY 0.553191 (-7075 1925);
DISPLAY INVISIBLE (-7075 1925);
FORCEPROP 1 LAST PATH I118
J 2
(-7000 1875);
DISPLAY 0.723404 (-7000 1875);
DISPLAY INVISIBLE (-7000 1875);
FORCEPROP 1 LAST PART_NUMBER SP_CH4221MEE01
J 2
(-7116 1963);
DISPLAY 0.574468 (-7116 1963);
PAINT GREEN (-7116 1963);
DISPLAY INVISIBLE (-7116 1963);
FORCEPROP 1 LAST LOCATION C6522
J 0
(-6750 1950);
DISPLAY 1.021277 (-6750 1950);
DISPLAY INVISIBLE (-6750 1950);
FORCEADD Q_CAP_DIFFBUS..2
R 2
(-7000 1925);
FORCEPROP 1 LAST LOCATION C6521
J 2
(-6725 1925);
DISPLAY 0.723404 (-6725 1925);
PAINT GREEN (-6725 1925);
FORCEPROP 2 LAST $SEC 1
J 2
(-6825 2000);
DISPLAY 0.680851 (-6825 2000);
PAINT MONO (-6825 2000);
DISPLAY INVISIBLE (-6825 2000);
FORCEPROP 2 LAST CDS_SEC 1
J 2
(-6825 2000);
DISPLAY 0.680851 (-6825 2000);
DISPLAY INVISIBLE (-6825 2000);
FORCEPROP 2 LASTPIN (-6925 1925) $PN 1
J 0
(-6915 1935);
DISPLAY 0.808511 (-6915 1935);
FORCEPROP 2 LASTPIN (-7075 1925) $PN 2
J 2
(-7085 1935);
DISPLAY 0.808511 (-7085 1935);
FORCEPROP 2 LAST VALUE DIFF BUS_0.22UF
J 2
(-7150 1925);
DISPLAY 0.553191 (-7150 1925);
FORCEPROP 1 LAST CDS_LMAN_SYM_OUTLINE -25,50,25,-50
J 2
(-7000 1925);
DISPLAY 0.468085 (-7000 1925);
PAINT GREEN (-7000 1925);
DISPLAY INVISIBLE (-7000 1925);
FORCEPROP 2 LAST CDS_LIB pure_quanta
J 2
(-7000 1925);
DISPLAY INVISIBLE (-7000 1925);
FORCEPROP 1 LAST PIN_NAMES_ROTATE TRUE
J 2
(-7000 1925);
DISPLAY 0.489362 (-7000 1925);
PAINT GREEN (-7000 1925);
DISPLAY INVISIBLE (-7000 1925);
FORCEPROP 2 LAST VOLTAGE 6.3V
J 2
(-7350 1975);
DISPLAY 0.553191 (-7350 1975);
DISPLAY INVISIBLE (-7350 1975);
FORCEPROP 1 LAST MATERIAL X6S
J 2
(-6991 2004);
DISPLAY 0.574468 (-6991 2004);
PAINT GREEN (-6991 2004);
DISPLAY INVISIBLE (-6991 2004);
FORCEPROP 2 LAST PACK_TYPE C0201
J 2
(-7175 1975);
DISPLAY 0.553191 (-7175 1975);
DISPLAY INVISIBLE (-7175 1975);
FORCEPROP 2 LAST TOLERANCE 20%
J 2
(-7075 1975);
DISPLAY 0.553191 (-7075 1975);
DISPLAY INVISIBLE (-7075 1975);
FORCEPROP 1 LAST PATH I119
J 2
(-7000 1925);
DISPLAY 0.723404 (-7000 1925);
DISPLAY INVISIBLE (-7000 1925);
FORCEPROP 1 LAST PART_NUMBER SP_CH4221MEE01
J 2
(-7116 2013);
DISPLAY 0.574468 (-7116 2013);
PAINT GREEN (-7116 2013);
DISPLAY INVISIBLE (-7116 2013);
FORCEPROP 1 LAST LOCATION C6521
J 0
(-6750 2000);
DISPLAY 1.021277 (-6750 2000);
DISPLAY INVISIBLE (-6750 2000);
FORCEADD TAP..1
(-7075 5350);
FORCEPROP 3 LASTPIN (-7125 5350) SIG_NAME P5E_CPU0_P0_TX_BUF_DP<13>
J 0
(-7115 5360);
DISPLAY 0.659574 (-7115 5360);
PAINT MONO (-7115 5360);
DISPLAY INVISIBLE (-7115 5360);
FORCEPROP 1 LASTPIN (-7125 5350) BN 13
J 0
(-7137 5358);
DISPLAY 0.680851 (-7137 5358);
PAINT GREEN (-7137 5358);
FORCEPROP 2 LAST CDS_LIB standard
J 0
(-7075 5350);
DISPLAY INVISIBLE (-7075 5350);
FORCEPROP 1 LAST BODY_TYPE PLUMBING
J 0
(-7075 5400);
DISPLAY 0.872340 (-7075 5400);
PAINT GREEN (-7075 5400);
DISPLAY INVISIBLE (-7075 5400);
FORCEPROP 1 LAST HDL_TAP TRUE
J 0
(-6750 5225);
DISPLAY 0.872340 (-6750 5225);
DISPLAY INVISIBLE (-6750 5225);
FORCEPROP 1 LAST PATH I12
J 0
(-7077 5350);
DISPLAY 0.872340 (-7077 5350);
PAINT GREEN (-7077 5350);
DISPLAY INVISIBLE (-7077 5350);
FORCEADD Q_CAP_DIFFBUS..2
R 2
(-7000 1725);
FORCEPROP 1 LAST LOCATION C6523
J 2
(-6725 1725);
DISPLAY 0.723404 (-6725 1725);
PAINT GREEN (-6725 1725);
FORCEPROP 2 LAST $SEC 1
J 2
(-6825 1800);
DISPLAY 0.680851 (-6825 1800);
PAINT MONO (-6825 1800);
DISPLAY INVISIBLE (-6825 1800);
FORCEPROP 2 LAST CDS_SEC 1
J 2
(-6825 1800);
DISPLAY 0.680851 (-6825 1800);
DISPLAY INVISIBLE (-6825 1800);
FORCEPROP 2 LASTPIN (-6925 1725) $PN 1
J 0
(-6915 1735);
DISPLAY 0.808511 (-6915 1735);
FORCEPROP 2 LASTPIN (-7075 1725) $PN 2
J 2
(-7085 1735);
DISPLAY 0.808511 (-7085 1735);
FORCEPROP 2 LAST VALUE DIFF BUS_0.22UF
J 2
(-7150 1725);
DISPLAY 0.553191 (-7150 1725);
FORCEPROP 1 LAST CDS_LMAN_SYM_OUTLINE -25,50,25,-50
J 2
(-7000 1725);
DISPLAY 0.468085 (-7000 1725);
PAINT GREEN (-7000 1725);
DISPLAY INVISIBLE (-7000 1725);
FORCEPROP 2 LAST CDS_LIB pure_quanta
J 2
(-7000 1725);
DISPLAY INVISIBLE (-7000 1725);
FORCEPROP 1 LAST PIN_NAMES_ROTATE TRUE
J 2
(-7000 1725);
DISPLAY 0.489362 (-7000 1725);
PAINT GREEN (-7000 1725);
DISPLAY INVISIBLE (-7000 1725);
FORCEPROP 2 LAST VOLTAGE 6.3V
J 2
(-7350 1775);
DISPLAY 0.553191 (-7350 1775);
DISPLAY INVISIBLE (-7350 1775);
FORCEPROP 1 LAST MATERIAL X6S
J 2
(-6991 1804);
DISPLAY 0.574468 (-6991 1804);
PAINT GREEN (-6991 1804);
DISPLAY INVISIBLE (-6991 1804);
FORCEPROP 2 LAST PACK_TYPE C0201
J 2
(-7175 1775);
DISPLAY 0.553191 (-7175 1775);
DISPLAY INVISIBLE (-7175 1775);
FORCEPROP 2 LAST TOLERANCE 20%
J 2
(-7075 1775);
DISPLAY 0.553191 (-7075 1775);
DISPLAY INVISIBLE (-7075 1775);
FORCEPROP 1 LAST PATH I120
J 2
(-7000 1725);
DISPLAY 0.723404 (-7000 1725);
DISPLAY INVISIBLE (-7000 1725);
FORCEPROP 1 LAST PART_NUMBER SP_CH4221MEE01
J 2
(-7116 1813);
DISPLAY 0.574468 (-7116 1813);
PAINT GREEN (-7116 1813);
DISPLAY INVISIBLE (-7116 1813);
FORCEPROP 1 LAST LOCATION C6523
J 0
(-6750 1800);
DISPLAY 1.021277 (-6750 1800);
DISPLAY INVISIBLE (-6750 1800);
FORCEADD Q_CAP_DIFFBUS..2
R 2
(-7000 1675);
FORCEPROP 1 LAST LOCATION C6524
J 2
(-6725 1675);
DISPLAY 0.723404 (-6725 1675);
PAINT GREEN (-6725 1675);
FORCEPROP 2 LAST $SEC 1
J 2
(-6825 1750);
DISPLAY 0.680851 (-6825 1750);
PAINT MONO (-6825 1750);
DISPLAY INVISIBLE (-6825 1750);
FORCEPROP 2 LAST CDS_SEC 1
J 2
(-6825 1750);
DISPLAY 0.680851 (-6825 1750);
DISPLAY INVISIBLE (-6825 1750);
FORCEPROP 2 LASTPIN (-6925 1675) $PN 1
J 0
(-6915 1685);
DISPLAY 0.808511 (-6915 1685);
FORCEPROP 2 LASTPIN (-7075 1675) $PN 2
J 2
(-7085 1685);
DISPLAY 0.808511 (-7085 1685);
FORCEPROP 2 LAST VALUE DIFF BUS_0.22UF
J 2
(-7150 1675);
DISPLAY 0.553191 (-7150 1675);
FORCEPROP 1 LAST CDS_LMAN_SYM_OUTLINE -25,50,25,-50
J 2
(-7000 1675);
DISPLAY 0.468085 (-7000 1675);
PAINT GREEN (-7000 1675);
DISPLAY INVISIBLE (-7000 1675);
FORCEPROP 2 LAST CDS_LIB pure_quanta
J 2
(-7000 1675);
DISPLAY INVISIBLE (-7000 1675);
FORCEPROP 1 LAST PIN_NAMES_ROTATE TRUE
J 2
(-7000 1675);
DISPLAY 0.489362 (-7000 1675);
PAINT GREEN (-7000 1675);
DISPLAY INVISIBLE (-7000 1675);
FORCEPROP 2 LAST VOLTAGE 6.3V
J 2
(-7350 1725);
DISPLAY 0.553191 (-7350 1725);
DISPLAY INVISIBLE (-7350 1725);
FORCEPROP 1 LAST MATERIAL X6S
J 2
(-6991 1754);
DISPLAY 0.574468 (-6991 1754);
PAINT GREEN (-6991 1754);
DISPLAY INVISIBLE (-6991 1754);
FORCEPROP 2 LAST PACK_TYPE C0201
J 2
(-7175 1725);
DISPLAY 0.553191 (-7175 1725);
DISPLAY INVISIBLE (-7175 1725);
FORCEPROP 2 LAST TOLERANCE 20%
J 2
(-7075 1725);
DISPLAY 0.553191 (-7075 1725);
DISPLAY INVISIBLE (-7075 1725);
FORCEPROP 1 LAST PATH I121
J 2
(-7000 1675);
DISPLAY 0.723404 (-7000 1675);
DISPLAY INVISIBLE (-7000 1675);
FORCEPROP 1 LAST PART_NUMBER SP_CH4221MEE01
J 2
(-7116 1763);
DISPLAY 0.574468 (-7116 1763);
PAINT GREEN (-7116 1763);
DISPLAY INVISIBLE (-7116 1763);
FORCEPROP 1 LAST LOCATION C6524
J 0
(-6750 1750);
DISPLAY 1.021277 (-6750 1750);
DISPLAY INVISIBLE (-6750 1750);
FORCEADD Q_CAP_DIFFBUS..2
R 2
(-7000 1475);
FORCEPROP 1 LAST LOCATION C6526
J 2
(-6725 1475);
DISPLAY 0.723404 (-6725 1475);
PAINT GREEN (-6725 1475);
FORCEPROP 2 LAST $SEC 1
J 2
(-6825 1550);
DISPLAY 0.680851 (-6825 1550);
PAINT MONO (-6825 1550);
DISPLAY INVISIBLE (-6825 1550);
FORCEPROP 2 LAST CDS_SEC 1
J 2
(-6825 1550);
DISPLAY 0.680851 (-6825 1550);
DISPLAY INVISIBLE (-6825 1550);
FORCEPROP 2 LASTPIN (-6925 1475) $PN 1
J 0
(-6915 1485);
DISPLAY 0.808511 (-6915 1485);
FORCEPROP 2 LASTPIN (-7075 1475) $PN 2
J 2
(-7085 1485);
DISPLAY 0.808511 (-7085 1485);
FORCEPROP 2 LAST VALUE DIFF BUS_0.22UF
J 2
(-7150 1475);
DISPLAY 0.553191 (-7150 1475);
FORCEPROP 2 LAST CDS_LIB pure_quanta
J 2
(-7000 1475);
DISPLAY INVISIBLE (-7000 1475);
FORCEPROP 1 LAST CDS_LMAN_SYM_OUTLINE -25,50,25,-50
J 2
(-7000 1475);
DISPLAY 0.468085 (-7000 1475);
PAINT GREEN (-7000 1475);
DISPLAY INVISIBLE (-7000 1475);
FORCEPROP 1 LAST PIN_NAMES_ROTATE TRUE
J 2
(-7000 1475);
DISPLAY 0.489362 (-7000 1475);
PAINT GREEN (-7000 1475);
DISPLAY INVISIBLE (-7000 1475);
FORCEPROP 2 LAST VOLTAGE 6.3V
J 2
(-7350 1525);
DISPLAY 0.553191 (-7350 1525);
DISPLAY INVISIBLE (-7350 1525);
FORCEPROP 1 LAST MATERIAL X6S
J 2
(-6991 1554);
DISPLAY 0.574468 (-6991 1554);
PAINT GREEN (-6991 1554);
DISPLAY INVISIBLE (-6991 1554);
FORCEPROP 2 LAST PACK_TYPE C0201
J 2
(-7175 1525);
DISPLAY 0.553191 (-7175 1525);
DISPLAY INVISIBLE (-7175 1525);
FORCEPROP 2 LAST TOLERANCE 20%
J 2
(-7075 1525);
DISPLAY 0.553191 (-7075 1525);
DISPLAY INVISIBLE (-7075 1525);
FORCEPROP 1 LAST PATH I122
J 2
(-7000 1475);
DISPLAY 0.723404 (-7000 1475);
DISPLAY INVISIBLE (-7000 1475);
FORCEPROP 1 LAST PART_NUMBER SP_CH4221MEE01
J 2
(-7116 1563);
DISPLAY 0.574468 (-7116 1563);
PAINT GREEN (-7116 1563);
DISPLAY INVISIBLE (-7116 1563);
FORCEPROP 1 LAST LOCATION C6526
J 0
(-6750 1550);
DISPLAY 1.021277 (-6750 1550);
DISPLAY INVISIBLE (-6750 1550);
FORCEADD Q_CAP_DIFFBUS..2
R 2
(-7000 1525);
FORCEPROP 1 LAST LOCATION C6525
J 2
(-6725 1525);
DISPLAY 0.723404 (-6725 1525);
PAINT GREEN (-6725 1525);
FORCEPROP 2 LAST $SEC 1
J 2
(-6825 1600);
DISPLAY 0.680851 (-6825 1600);
PAINT MONO (-6825 1600);
DISPLAY INVISIBLE (-6825 1600);
FORCEPROP 2 LAST CDS_SEC 1
J 2
(-6825 1600);
DISPLAY 0.680851 (-6825 1600);
DISPLAY INVISIBLE (-6825 1600);
FORCEPROP 2 LASTPIN (-6925 1525) $PN 1
J 0
(-6915 1535);
DISPLAY 0.808511 (-6915 1535);
FORCEPROP 2 LASTPIN (-7075 1525) $PN 2
J 2
(-7085 1535);
DISPLAY 0.808511 (-7085 1535);
FORCEPROP 2 LAST VALUE DIFF BUS_0.22UF
J 2
(-7150 1525);
DISPLAY 0.553191 (-7150 1525);
FORCEPROP 2 LAST CDS_LIB pure_quanta
J 2
(-7000 1525);
DISPLAY INVISIBLE (-7000 1525);
FORCEPROP 1 LAST CDS_LMAN_SYM_OUTLINE -25,50,25,-50
J 2
(-7000 1525);
DISPLAY 0.468085 (-7000 1525);
PAINT GREEN (-7000 1525);
DISPLAY INVISIBLE (-7000 1525);
FORCEPROP 1 LAST PIN_NAMES_ROTATE TRUE
J 2
(-7000 1525);
DISPLAY 0.489362 (-7000 1525);
PAINT GREEN (-7000 1525);
DISPLAY INVISIBLE (-7000 1525);
FORCEPROP 2 LAST VOLTAGE 6.3V
J 2
(-7350 1575);
DISPLAY 0.553191 (-7350 1575);
DISPLAY INVISIBLE (-7350 1575);
FORCEPROP 1 LAST MATERIAL X6S
J 2
(-6991 1604);
DISPLAY 0.574468 (-6991 1604);
PAINT GREEN (-6991 1604);
DISPLAY INVISIBLE (-6991 1604);
FORCEPROP 2 LAST PACK_TYPE C0201
J 2
(-7175 1575);
DISPLAY 0.553191 (-7175 1575);
DISPLAY INVISIBLE (-7175 1575);
FORCEPROP 2 LAST TOLERANCE 20%
J 2
(-7075 1575);
DISPLAY 0.553191 (-7075 1575);
DISPLAY INVISIBLE (-7075 1575);
FORCEPROP 1 LAST PATH I123
J 2
(-7000 1525);
DISPLAY 0.723404 (-7000 1525);
DISPLAY INVISIBLE (-7000 1525);
FORCEPROP 1 LAST PART_NUMBER SP_CH4221MEE01
J 2
(-7116 1613);
DISPLAY 0.574468 (-7116 1613);
PAINT GREEN (-7116 1613);
DISPLAY INVISIBLE (-7116 1613);
FORCEPROP 1 LAST LOCATION C6525
J 0
(-6750 1600);
DISPLAY 1.021277 (-6750 1600);
DISPLAY INVISIBLE (-6750 1600);
FORCEADD Q_CAP_DIFFBUS..2
R 2
(-7000 1325);
FORCEPROP 1 LAST LOCATION C6527
J 2
(-6725 1325);
DISPLAY 0.723404 (-6725 1325);
PAINT GREEN (-6725 1325);
FORCEPROP 2 LAST $SEC 1
J 2
(-6825 1400);
DISPLAY 0.680851 (-6825 1400);
PAINT MONO (-6825 1400);
DISPLAY INVISIBLE (-6825 1400);
FORCEPROP 2 LAST CDS_SEC 1
J 2
(-6825 1400);
DISPLAY 0.680851 (-6825 1400);
DISPLAY INVISIBLE (-6825 1400);
FORCEPROP 2 LASTPIN (-6925 1325) $PN 1
J 0
(-6915 1335);
DISPLAY 0.808511 (-6915 1335);
FORCEPROP 2 LASTPIN (-7075 1325) $PN 2
J 2
(-7085 1335);
DISPLAY 0.808511 (-7085 1335);
FORCEPROP 2 LAST VALUE DIFF BUS_0.22UF
J 2
(-7150 1325);
DISPLAY 0.553191 (-7150 1325);
FORCEPROP 1 LAST CDS_LMAN_SYM_OUTLINE -25,50,25,-50
J 2
(-7000 1325);
DISPLAY 0.468085 (-7000 1325);
PAINT GREEN (-7000 1325);
DISPLAY INVISIBLE (-7000 1325);
FORCEPROP 2 LAST CDS_LIB pure_quanta
J 2
(-7000 1325);
DISPLAY INVISIBLE (-7000 1325);
FORCEPROP 1 LAST PIN_NAMES_ROTATE TRUE
J 2
(-7000 1325);
DISPLAY 0.489362 (-7000 1325);
PAINT GREEN (-7000 1325);
DISPLAY INVISIBLE (-7000 1325);
FORCEPROP 2 LAST VOLTAGE 6.3V
J 2
(-7350 1375);
DISPLAY 0.553191 (-7350 1375);
DISPLAY INVISIBLE (-7350 1375);
FORCEPROP 1 LAST MATERIAL X6S
J 2
(-6991 1404);
DISPLAY 0.574468 (-6991 1404);
PAINT GREEN (-6991 1404);
DISPLAY INVISIBLE (-6991 1404);
FORCEPROP 2 LAST PACK_TYPE C0201
J 2
(-7175 1375);
DISPLAY 0.553191 (-7175 1375);
DISPLAY INVISIBLE (-7175 1375);
FORCEPROP 2 LAST TOLERANCE 20%
J 2
(-7075 1375);
DISPLAY 0.553191 (-7075 1375);
DISPLAY INVISIBLE (-7075 1375);
FORCEPROP 1 LAST PATH I124
J 2
(-7000 1325);
DISPLAY 0.723404 (-7000 1325);
DISPLAY INVISIBLE (-7000 1325);
FORCEPROP 1 LAST PART_NUMBER SP_CH4221MEE01
J 2
(-7116 1413);
DISPLAY 0.574468 (-7116 1413);
PAINT GREEN (-7116 1413);
DISPLAY INVISIBLE (-7116 1413);
FORCEPROP 1 LAST LOCATION C6527
J 0
(-6750 1400);
DISPLAY 1.021277 (-6750 1400);
DISPLAY INVISIBLE (-6750 1400);
FORCEADD Q_CAP_DIFFBUS..2
R 2
(-7000 1275);
FORCEPROP 1 LAST LOCATION C6528
J 2
(-6725 1275);
DISPLAY 0.723404 (-6725 1275);
PAINT GREEN (-6725 1275);
FORCEPROP 2 LAST $SEC 1
J 2
(-6825 1350);
DISPLAY 0.680851 (-6825 1350);
PAINT MONO (-6825 1350);
DISPLAY INVISIBLE (-6825 1350);
FORCEPROP 2 LAST CDS_SEC 1
J 2
(-6825 1350);
DISPLAY 0.680851 (-6825 1350);
DISPLAY INVISIBLE (-6825 1350);
FORCEPROP 2 LASTPIN (-6925 1275) $PN 1
J 0
(-6915 1285);
DISPLAY 0.808511 (-6915 1285);
FORCEPROP 2 LASTPIN (-7075 1275) $PN 2
J 2
(-7085 1285);
DISPLAY 0.808511 (-7085 1285);
FORCEPROP 2 LAST VALUE DIFF BUS_0.22UF
J 2
(-7150 1275);
DISPLAY 0.553191 (-7150 1275);
FORCEPROP 1 LAST CDS_LMAN_SYM_OUTLINE -25,50,25,-50
J 2
(-7000 1275);
DISPLAY 0.468085 (-7000 1275);
PAINT GREEN (-7000 1275);
DISPLAY INVISIBLE (-7000 1275);
FORCEPROP 2 LAST CDS_LIB pure_quanta
J 2
(-7000 1275);
DISPLAY INVISIBLE (-7000 1275);
FORCEPROP 1 LAST PIN_NAMES_ROTATE TRUE
J 2
(-7000 1275);
DISPLAY 0.489362 (-7000 1275);
PAINT GREEN (-7000 1275);
DISPLAY INVISIBLE (-7000 1275);
FORCEPROP 2 LAST VOLTAGE 6.3V
J 2
(-7350 1325);
DISPLAY 0.553191 (-7350 1325);
DISPLAY INVISIBLE (-7350 1325);
FORCEPROP 1 LAST MATERIAL X6S
J 2
(-6991 1354);
DISPLAY 0.574468 (-6991 1354);
PAINT GREEN (-6991 1354);
DISPLAY INVISIBLE (-6991 1354);
FORCEPROP 2 LAST PACK_TYPE C0201
J 2
(-7175 1325);
DISPLAY 0.553191 (-7175 1325);
DISPLAY INVISIBLE (-7175 1325);
FORCEPROP 2 LAST TOLERANCE 20%
J 2
(-7075 1325);
DISPLAY 0.553191 (-7075 1325);
DISPLAY INVISIBLE (-7075 1325);
FORCEPROP 1 LAST PATH I125
J 2
(-7000 1275);
DISPLAY 0.723404 (-7000 1275);
DISPLAY INVISIBLE (-7000 1275);
FORCEPROP 1 LAST PART_NUMBER SP_CH4221MEE01
J 2
(-7116 1363);
DISPLAY 0.574468 (-7116 1363);
PAINT GREEN (-7116 1363);
DISPLAY INVISIBLE (-7116 1363);
FORCEPROP 1 LAST LOCATION C6528
J 0
(-6750 1350);
DISPLAY 1.021277 (-6750 1350);
DISPLAY INVISIBLE (-6750 1350);
FORCEADD Q_CAP_DIFFBUS..2
R 2
(-7000 1125);
FORCEPROP 1 LAST LOCATION C6529
J 2
(-6725 1125);
DISPLAY 0.723404 (-6725 1125);
PAINT GREEN (-6725 1125);
FORCEPROP 2 LAST $SEC 1
J 2
(-6825 1200);
DISPLAY 0.680851 (-6825 1200);
PAINT MONO (-6825 1200);
DISPLAY INVISIBLE (-6825 1200);
FORCEPROP 2 LAST CDS_SEC 1
J 2
(-6825 1200);
DISPLAY 0.680851 (-6825 1200);
DISPLAY INVISIBLE (-6825 1200);
FORCEPROP 2 LASTPIN (-6925 1125) $PN 1
J 0
(-6915 1135);
DISPLAY 0.808511 (-6915 1135);
FORCEPROP 2 LASTPIN (-7075 1125) $PN 2
J 2
(-7085 1135);
DISPLAY 0.808511 (-7085 1135);
FORCEPROP 2 LAST VALUE DIFF BUS_0.22UF
J 2
(-7150 1125);
DISPLAY 0.553191 (-7150 1125);
FORCEPROP 2 LAST CDS_LIB pure_quanta
J 2
(-7000 1125);
DISPLAY INVISIBLE (-7000 1125);
FORCEPROP 1 LAST CDS_LMAN_SYM_OUTLINE -25,50,25,-50
J 2
(-7000 1125);
DISPLAY 0.468085 (-7000 1125);
PAINT GREEN (-7000 1125);
DISPLAY INVISIBLE (-7000 1125);
FORCEPROP 1 LAST PIN_NAMES_ROTATE TRUE
J 2
(-7000 1125);
DISPLAY 0.489362 (-7000 1125);
PAINT GREEN (-7000 1125);
DISPLAY INVISIBLE (-7000 1125);
FORCEPROP 2 LAST VOLTAGE 6.3V
J 2
(-7350 1175);
DISPLAY 0.553191 (-7350 1175);
DISPLAY INVISIBLE (-7350 1175);
FORCEPROP 1 LAST MATERIAL X6S
J 2
(-6991 1204);
DISPLAY 0.574468 (-6991 1204);
PAINT GREEN (-6991 1204);
DISPLAY INVISIBLE (-6991 1204);
FORCEPROP 2 LAST PACK_TYPE C0201
J 2
(-7175 1175);
DISPLAY 0.553191 (-7175 1175);
DISPLAY INVISIBLE (-7175 1175);
FORCEPROP 2 LAST TOLERANCE 20%
J 2
(-7075 1175);
DISPLAY 0.553191 (-7075 1175);
DISPLAY INVISIBLE (-7075 1175);
FORCEPROP 1 LAST PATH I126
J 2
(-7000 1125);
DISPLAY 0.723404 (-7000 1125);
DISPLAY INVISIBLE (-7000 1125);
FORCEPROP 1 LAST PART_NUMBER SP_CH4221MEE01
J 2
(-7116 1213);
DISPLAY 0.574468 (-7116 1213);
PAINT GREEN (-7116 1213);
DISPLAY INVISIBLE (-7116 1213);
FORCEPROP 1 LAST LOCATION C6529
J 0
(-6750 1200);
DISPLAY 1.021277 (-6750 1200);
DISPLAY INVISIBLE (-6750 1200);
FORCEADD Q_CAP_DIFFBUS..2
R 2
(-7000 1075);
FORCEPROP 1 LAST LOCATION C6530
J 2
(-6725 1075);
DISPLAY 0.723404 (-6725 1075);
PAINT GREEN (-6725 1075);
FORCEPROP 2 LAST $SEC 1
J 2
(-6825 1150);
DISPLAY 0.680851 (-6825 1150);
PAINT MONO (-6825 1150);
DISPLAY INVISIBLE (-6825 1150);
FORCEPROP 2 LAST CDS_SEC 1
J 2
(-6825 1150);
DISPLAY 0.680851 (-6825 1150);
DISPLAY INVISIBLE (-6825 1150);
FORCEPROP 2 LASTPIN (-6925 1075) $PN 1
J 0
(-6915 1085);
DISPLAY 0.808511 (-6915 1085);
FORCEPROP 2 LASTPIN (-7075 1075) $PN 2
J 2
(-7085 1085);
DISPLAY 0.808511 (-7085 1085);
FORCEPROP 2 LAST VALUE DIFF BUS_0.22UF
J 2
(-7150 1075);
DISPLAY 0.553191 (-7150 1075);
FORCEPROP 1 LAST CDS_LMAN_SYM_OUTLINE -25,50,25,-50
J 2
(-7000 1075);
DISPLAY 0.468085 (-7000 1075);
PAINT GREEN (-7000 1075);
DISPLAY INVISIBLE (-7000 1075);
FORCEPROP 2 LAST CDS_LIB pure_quanta
J 2
(-7000 1075);
DISPLAY INVISIBLE (-7000 1075);
FORCEPROP 1 LAST PIN_NAMES_ROTATE TRUE
J 2
(-7000 1075);
DISPLAY 0.489362 (-7000 1075);
PAINT GREEN (-7000 1075);
DISPLAY INVISIBLE (-7000 1075);
FORCEPROP 2 LAST VOLTAGE 6.3V
J 2
(-7350 1125);
DISPLAY 0.553191 (-7350 1125);
DISPLAY INVISIBLE (-7350 1125);
FORCEPROP 1 LAST MATERIAL X6S
J 2
(-6991 1154);
DISPLAY 0.574468 (-6991 1154);
PAINT GREEN (-6991 1154);
DISPLAY INVISIBLE (-6991 1154);
FORCEPROP 2 LAST PACK_TYPE C0201
J 2
(-7175 1125);
DISPLAY 0.553191 (-7175 1125);
DISPLAY INVISIBLE (-7175 1125);
FORCEPROP 2 LAST TOLERANCE 20%
J 2
(-7075 1125);
DISPLAY 0.553191 (-7075 1125);
DISPLAY INVISIBLE (-7075 1125);
FORCEPROP 1 LAST PATH I127
J 2
(-7000 1075);
DISPLAY 0.723404 (-7000 1075);
DISPLAY INVISIBLE (-7000 1075);
FORCEPROP 1 LAST PART_NUMBER SP_CH4221MEE01
J 2
(-7116 1163);
DISPLAY 0.574468 (-7116 1163);
PAINT GREEN (-7116 1163);
DISPLAY INVISIBLE (-7116 1163);
FORCEPROP 1 LAST LOCATION C6530
J 0
(-6750 1150);
DISPLAY 1.021277 (-6750 1150);
DISPLAY INVISIBLE (-6750 1150);
FORCEADD TAP..1
(-6250 875);
FORCEPROP 3 LASTPIN (-6300 875) SIG_NAME P5E_CPU0_P0_TX_BUF_C_DN<15>
J 0
(-6290 885);
DISPLAY 0.659574 (-6290 885);
PAINT MONO (-6290 885);
DISPLAY INVISIBLE (-6290 885);
FORCEPROP 1 LASTPIN (-6300 875) BN 15
J 0
(-6312 883);
DISPLAY 0.680851 (-6312 883);
PAINT GREEN (-6312 883);
FORCEPROP 2 LAST CDS_LIB standard
J 0
(-6250 875);
DISPLAY INVISIBLE (-6250 875);
FORCEPROP 1 LAST BODY_TYPE PLUMBING
J 0
(-6250 925);
DISPLAY 0.872340 (-6250 925);
PAINT GREEN (-6250 925);
DISPLAY INVISIBLE (-6250 925);
FORCEPROP 1 LAST HDL_TAP TRUE
J 0
(-5925 750);
DISPLAY 0.872340 (-5925 750);
DISPLAY INVISIBLE (-5925 750);
FORCEPROP 1 LAST PATH I128
J 0
(-6252 875);
DISPLAY 0.872340 (-6252 875);
PAINT GREEN (-6252 875);
DISPLAY INVISIBLE (-6252 875);
FORCEADD Q_CAP_DIFFBUS..2
R 2
(-7000 925);
FORCEPROP 1 LAST LOCATION C6531
J 2
(-6725 925);
DISPLAY 0.723404 (-6725 925);
PAINT GREEN (-6725 925);
FORCEPROP 2 LAST $SEC 1
J 2
(-6825 1000);
DISPLAY 0.680851 (-6825 1000);
PAINT MONO (-6825 1000);
DISPLAY INVISIBLE (-6825 1000);
FORCEPROP 2 LAST CDS_SEC 1
J 2
(-6825 1000);
DISPLAY 0.680851 (-6825 1000);
DISPLAY INVISIBLE (-6825 1000);
FORCEPROP 2 LASTPIN (-6925 925) $PN 1
J 0
(-6915 935);
DISPLAY 0.808511 (-6915 935);
FORCEPROP 2 LASTPIN (-7075 925) $PN 2
J 2
(-7085 935);
DISPLAY 0.808511 (-7085 935);
FORCEPROP 2 LAST VALUE DIFF BUS_0.22UF
J 2
(-7150 925);
DISPLAY 0.553191 (-7150 925);
FORCEPROP 1 LAST CDS_LMAN_SYM_OUTLINE -25,50,25,-50
J 2
(-7000 925);
DISPLAY 0.468085 (-7000 925);
PAINT GREEN (-7000 925);
DISPLAY INVISIBLE (-7000 925);
FORCEPROP 2 LAST CDS_LIB pure_quanta
J 2
(-7000 925);
DISPLAY INVISIBLE (-7000 925);
FORCEPROP 1 LAST PIN_NAMES_ROTATE TRUE
J 2
(-7000 925);
DISPLAY 0.489362 (-7000 925);
PAINT GREEN (-7000 925);
DISPLAY INVISIBLE (-7000 925);
FORCEPROP 2 LAST VOLTAGE 6.3V
J 2
(-7350 975);
DISPLAY 0.553191 (-7350 975);
DISPLAY INVISIBLE (-7350 975);
FORCEPROP 1 LAST MATERIAL X6S
J 2
(-6991 1004);
DISPLAY 0.574468 (-6991 1004);
PAINT GREEN (-6991 1004);
DISPLAY INVISIBLE (-6991 1004);
FORCEPROP 2 LAST PACK_TYPE C0201
J 2
(-7175 975);
DISPLAY 0.553191 (-7175 975);
DISPLAY INVISIBLE (-7175 975);
FORCEPROP 2 LAST TOLERANCE 20%
J 2
(-7075 975);
DISPLAY 0.553191 (-7075 975);
DISPLAY INVISIBLE (-7075 975);
FORCEPROP 1 LAST PATH I129
J 2
(-7000 925);
DISPLAY 0.723404 (-7000 925);
DISPLAY INVISIBLE (-7000 925);
FORCEPROP 1 LAST PART_NUMBER SP_CH4221MEE01
J 2
(-7116 1013);
DISPLAY 0.574468 (-7116 1013);
PAINT GREEN (-7116 1013);
DISPLAY INVISIBLE (-7116 1013);
FORCEPROP 1 LAST LOCATION C6531
J 0
(-6750 1000);
DISPLAY 1.021277 (-6750 1000);
DISPLAY INVISIBLE (-6750 1000);
FORCEADD TAP..1
(-6875 5250);
FORCEPROP 3 LASTPIN (-6925 5250) SIG_NAME P5E_CPU0_P0_TX_BUF_DN<13>
J 0
(-6915 5260);
DISPLAY 0.659574 (-6915 5260);
PAINT MONO (-6915 5260);
DISPLAY INVISIBLE (-6915 5260);
FORCEPROP 1 LASTPIN (-6925 5250) BN 13
J 0
(-6937 5258);
DISPLAY 0.680851 (-6937 5258);
PAINT GREEN (-6937 5258);
FORCEPROP 2 LAST CDS_LIB standard
J 0
(-6875 5250);
DISPLAY INVISIBLE (-6875 5250);
FORCEPROP 1 LAST BODY_TYPE PLUMBING
J 0
(-6875 5300);
DISPLAY 0.872340 (-6875 5300);
PAINT GREEN (-6875 5300);
DISPLAY INVISIBLE (-6875 5300);
FORCEPROP 1 LAST HDL_TAP TRUE
J 0
(-6550 5125);
DISPLAY 0.872340 (-6550 5125);
DISPLAY INVISIBLE (-6550 5125);
FORCEPROP 1 LAST PATH I13
J 0
(-6877 5250);
DISPLAY 0.872340 (-6877 5250);
PAINT GREEN (-6877 5250);
DISPLAY INVISIBLE (-6877 5250);
FORCEADD Q_CAP_DIFFBUS..2
R 2
(-7000 875);
FORCEPROP 1 LAST LOCATION C6532
J 2
(-6725 875);
DISPLAY 0.723404 (-6725 875);
PAINT GREEN (-6725 875);
FORCEPROP 2 LAST $SEC 1
J 2
(-6825 950);
DISPLAY 0.680851 (-6825 950);
PAINT MONO (-6825 950);
DISPLAY INVISIBLE (-6825 950);
FORCEPROP 2 LAST CDS_SEC 1
J 2
(-6825 950);
DISPLAY 0.680851 (-6825 950);
DISPLAY INVISIBLE (-6825 950);
FORCEPROP 2 LASTPIN (-6925 875) $PN 1
J 0
(-6915 885);
DISPLAY 0.808511 (-6915 885);
FORCEPROP 2 LASTPIN (-7075 875) $PN 2
J 2
(-7085 885);
DISPLAY 0.808511 (-7085 885);
FORCEPROP 2 LAST VALUE DIFF BUS_0.22UF
J 2
(-7150 875);
DISPLAY 0.553191 (-7150 875);
FORCEPROP 1 LAST CDS_LMAN_SYM_OUTLINE -25,50,25,-50
J 2
(-7000 875);
DISPLAY 0.468085 (-7000 875);
PAINT GREEN (-7000 875);
DISPLAY INVISIBLE (-7000 875);
FORCEPROP 2 LAST CDS_LIB pure_quanta
J 2
(-7000 875);
DISPLAY INVISIBLE (-7000 875);
FORCEPROP 1 LAST PIN_NAMES_ROTATE TRUE
J 2
(-7000 875);
DISPLAY 0.489362 (-7000 875);
PAINT GREEN (-7000 875);
DISPLAY INVISIBLE (-7000 875);
FORCEPROP 2 LAST VOLTAGE 6.3V
J 2
(-7350 925);
DISPLAY 0.553191 (-7350 925);
DISPLAY INVISIBLE (-7350 925);
FORCEPROP 1 LAST MATERIAL X6S
J 2
(-6991 954);
DISPLAY 0.574468 (-6991 954);
PAINT GREEN (-6991 954);
DISPLAY INVISIBLE (-6991 954);
FORCEPROP 2 LAST PACK_TYPE C0201
J 2
(-7175 925);
DISPLAY 0.553191 (-7175 925);
DISPLAY INVISIBLE (-7175 925);
FORCEPROP 2 LAST TOLERANCE 20%
J 2
(-7075 925);
DISPLAY 0.553191 (-7075 925);
DISPLAY INVISIBLE (-7075 925);
FORCEPROP 1 LAST PATH I130
J 2
(-7000 875);
DISPLAY 0.723404 (-7000 875);
DISPLAY INVISIBLE (-7000 875);
FORCEPROP 1 LAST PART_NUMBER SP_CH4221MEE01
J 2
(-7116 963);
DISPLAY 0.574468 (-7116 963);
PAINT GREEN (-7116 963);
DISPLAY INVISIBLE (-7116 963);
FORCEPROP 1 LAST LOCATION C6532
J 0
(-6750 950);
DISPLAY 1.021277 (-6750 950);
DISPLAY INVISIBLE (-6750 950);
FORCEADD TAP..1
R 2
(-7725 1925);
FORCEPROP 3 LASTPIN (-7675 1925) SIG_NAME P5E_CPU0_P0_TX_BUF_DP<10>
J 0
(-7665 1935);
DISPLAY 0.659574 (-7665 1935);
PAINT MONO (-7665 1935);
DISPLAY INVISIBLE (-7665 1935);
FORCEPROP 1 LASTPIN (-7675 1925) BN 10
J 2
(-7663 1933);
DISPLAY 0.680851 (-7663 1933);
PAINT GREEN (-7663 1933);
FORCEPROP 2 LAST CDS_LIB standard
J 0
(-7725 1925);
DISPLAY INVISIBLE (-7725 1925);
FORCEPROP 1 LAST BODY_TYPE PLUMBING
J 2
(-7725 1975);
DISPLAY 0.872340 (-7725 1975);
PAINT GREEN (-7725 1975);
DISPLAY INVISIBLE (-7725 1975);
FORCEPROP 1 LAST HDL_TAP TRUE
J 2
(-8050 1800);
DISPLAY 0.872340 (-8050 1800);
DISPLAY INVISIBLE (-8050 1800);
FORCEPROP 1 LAST PATH I131
J 2
(-7723 1925);
DISPLAY 0.872340 (-7723 1925);
PAINT GREEN (-7723 1925);
DISPLAY INVISIBLE (-7723 1925);
FORCEADD TAP..1
R 2
(-7725 1725);
FORCEPROP 3 LASTPIN (-7675 1725) SIG_NAME P5E_CPU0_P0_TX_BUF_DP<11>
J 0
(-7665 1735);
DISPLAY 0.659574 (-7665 1735);
PAINT MONO (-7665 1735);
DISPLAY INVISIBLE (-7665 1735);
FORCEPROP 1 LASTPIN (-7675 1725) BN 11
J 2
(-7663 1733);
DISPLAY 0.680851 (-7663 1733);
PAINT GREEN (-7663 1733);
FORCEPROP 2 LAST CDS_LIB standard
J 0
(-7725 1725);
DISPLAY INVISIBLE (-7725 1725);
FORCEPROP 1 LAST BODY_TYPE PLUMBING
J 2
(-7725 1775);
DISPLAY 0.872340 (-7725 1775);
PAINT GREEN (-7725 1775);
DISPLAY INVISIBLE (-7725 1775);
FORCEPROP 1 LAST HDL_TAP TRUE
J 2
(-8050 1600);
DISPLAY 0.872340 (-8050 1600);
DISPLAY INVISIBLE (-8050 1600);
FORCEPROP 1 LAST PATH I132
J 2
(-7723 1725);
DISPLAY 0.872340 (-7723 1725);
PAINT GREEN (-7723 1725);
DISPLAY INVISIBLE (-7723 1725);
FORCEADD TAP..1
R 2
(-7725 1525);
FORCEPROP 3 LASTPIN (-7675 1525) SIG_NAME P5E_CPU0_P0_TX_BUF_DP<12>
J 0
(-7665 1535);
DISPLAY 0.659574 (-7665 1535);
PAINT MONO (-7665 1535);
DISPLAY INVISIBLE (-7665 1535);
FORCEPROP 1 LASTPIN (-7675 1525) BN 12
J 2
(-7663 1533);
DISPLAY 0.680851 (-7663 1533);
PAINT GREEN (-7663 1533);
FORCEPROP 2 LAST CDS_LIB standard
J 0
(-7725 1525);
DISPLAY INVISIBLE (-7725 1525);
FORCEPROP 1 LAST BODY_TYPE PLUMBING
J 2
(-7725 1575);
DISPLAY 0.872340 (-7725 1575);
PAINT GREEN (-7725 1575);
DISPLAY INVISIBLE (-7725 1575);
FORCEPROP 1 LAST HDL_TAP TRUE
J 2
(-8050 1400);
DISPLAY 0.872340 (-8050 1400);
DISPLAY INVISIBLE (-8050 1400);
FORCEPROP 1 LAST PATH I133
J 2
(-7723 1525);
DISPLAY 0.872340 (-7723 1525);
PAINT GREEN (-7723 1525);
DISPLAY INVISIBLE (-7723 1525);
FORCEADD TAP..1
R 2
(-7725 1325);
FORCEPROP 3 LASTPIN (-7675 1325) SIG_NAME P5E_CPU0_P0_TX_BUF_DP<13>
J 0
(-7665 1335);
DISPLAY 0.659574 (-7665 1335);
PAINT MONO (-7665 1335);
DISPLAY INVISIBLE (-7665 1335);
FORCEPROP 1 LASTPIN (-7675 1325) BN 13
J 2
(-7663 1333);
DISPLAY 0.680851 (-7663 1333);
PAINT GREEN (-7663 1333);
FORCEPROP 2 LAST CDS_LIB standard
J 0
(-7725 1325);
DISPLAY INVISIBLE (-7725 1325);
FORCEPROP 1 LAST BODY_TYPE PLUMBING
J 2
(-7725 1375);
DISPLAY 0.872340 (-7725 1375);
PAINT GREEN (-7725 1375);
DISPLAY INVISIBLE (-7725 1375);
FORCEPROP 1 LAST HDL_TAP TRUE
J 2
(-8050 1200);
DISPLAY 0.872340 (-8050 1200);
DISPLAY INVISIBLE (-8050 1200);
FORCEPROP 1 LAST PATH I134
J 2
(-7723 1325);
DISPLAY 0.872340 (-7723 1325);
PAINT GREEN (-7723 1325);
DISPLAY INVISIBLE (-7723 1325);
FORCEADD TAP..1
R 2
(-7725 1125);
FORCEPROP 3 LASTPIN (-7675 1125) SIG_NAME P5E_CPU0_P0_TX_BUF_DP<14>
J 0
(-7665 1135);
DISPLAY 0.659574 (-7665 1135);
PAINT MONO (-7665 1135);
DISPLAY INVISIBLE (-7665 1135);
FORCEPROP 1 LASTPIN (-7675 1125) BN 14
J 2
(-7663 1133);
DISPLAY 0.680851 (-7663 1133);
PAINT GREEN (-7663 1133);
FORCEPROP 2 LAST CDS_LIB standard
J 0
(-7725 1125);
DISPLAY INVISIBLE (-7725 1125);
FORCEPROP 1 LAST BODY_TYPE PLUMBING
J 2
(-7725 1175);
DISPLAY 0.872340 (-7725 1175);
PAINT GREEN (-7725 1175);
DISPLAY INVISIBLE (-7725 1175);
FORCEPROP 1 LAST HDL_TAP TRUE
J 2
(-8050 1000);
DISPLAY 0.872340 (-8050 1000);
DISPLAY INVISIBLE (-8050 1000);
FORCEPROP 1 LAST PATH I135
J 2
(-7723 1125);
DISPLAY 0.872340 (-7723 1125);
PAINT GREEN (-7723 1125);
DISPLAY INVISIBLE (-7723 1125);
FORCEADD TAP..1
R 2
(-7725 925);
FORCEPROP 3 LASTPIN (-7675 925) SIG_NAME P5E_CPU0_P0_TX_BUF_DP<15>
J 0
(-7665 935);
DISPLAY 0.659574 (-7665 935);
PAINT MONO (-7665 935);
DISPLAY INVISIBLE (-7665 935);
FORCEPROP 1 LASTPIN (-7675 925) BN 15
J 2
(-7663 933);
DISPLAY 0.680851 (-7663 933);
PAINT GREEN (-7663 933);
FORCEPROP 2 LAST CDS_LIB standard
J 0
(-7725 925);
DISPLAY INVISIBLE (-7725 925);
FORCEPROP 1 LAST BODY_TYPE PLUMBING
J 2
(-7725 975);
DISPLAY 0.872340 (-7725 975);
PAINT GREEN (-7725 975);
DISPLAY INVISIBLE (-7725 975);
FORCEPROP 1 LAST HDL_TAP TRUE
J 2
(-8050 800);
DISPLAY 0.872340 (-8050 800);
DISPLAY INVISIBLE (-8050 800);
FORCEPROP 1 LAST PATH I136
J 2
(-7723 925);
DISPLAY 0.872340 (-7723 925);
PAINT GREEN (-7723 925);
DISPLAY INVISIBLE (-7723 925);
FORCEADD TAP..1
R 2
(-7975 1875);
FORCEPROP 3 LASTPIN (-7925 1875) SIG_NAME P5E_CPU0_P0_TX_BUF_DN<10>
J 0
(-7915 1885);
DISPLAY 0.659574 (-7915 1885);
PAINT MONO (-7915 1885);
DISPLAY INVISIBLE (-7915 1885);
FORCEPROP 1 LASTPIN (-7925 1875) BN 10
J 2
(-7913 1883);
DISPLAY 0.680851 (-7913 1883);
PAINT GREEN (-7913 1883);
FORCEPROP 2 LAST CDS_LIB standard
J 0
(-7975 1875);
DISPLAY INVISIBLE (-7975 1875);
FORCEPROP 1 LAST BODY_TYPE PLUMBING
J 2
(-7975 1925);
DISPLAY 0.872340 (-7975 1925);
PAINT GREEN (-7975 1925);
DISPLAY INVISIBLE (-7975 1925);
FORCEPROP 1 LAST HDL_TAP TRUE
J 2
(-8300 1750);
DISPLAY 0.872340 (-8300 1750);
DISPLAY INVISIBLE (-8300 1750);
FORCEPROP 1 LAST PATH I137
J 2
(-7973 1875);
DISPLAY 0.872340 (-7973 1875);
PAINT GREEN (-7973 1875);
DISPLAY INVISIBLE (-7973 1875);
FORCEADD TAP..1
R 2
(-7975 1675);
FORCEPROP 3 LASTPIN (-7925 1675) SIG_NAME P5E_CPU0_P0_TX_BUF_DN<11>
J 0
(-7915 1685);
DISPLAY 0.659574 (-7915 1685);
PAINT MONO (-7915 1685);
DISPLAY INVISIBLE (-7915 1685);
FORCEPROP 1 LASTPIN (-7925 1675) BN 11
J 2
(-7913 1683);
DISPLAY 0.680851 (-7913 1683);
PAINT GREEN (-7913 1683);
FORCEPROP 2 LAST CDS_LIB standard
J 0
(-7975 1675);
DISPLAY INVISIBLE (-7975 1675);
FORCEPROP 1 LAST BODY_TYPE PLUMBING
J 2
(-7975 1725);
DISPLAY 0.872340 (-7975 1725);
PAINT GREEN (-7975 1725);
DISPLAY INVISIBLE (-7975 1725);
FORCEPROP 1 LAST HDL_TAP TRUE
J 2
(-8300 1550);
DISPLAY 0.872340 (-8300 1550);
DISPLAY INVISIBLE (-8300 1550);
FORCEPROP 1 LAST PATH I138
J 2
(-7973 1675);
DISPLAY 0.872340 (-7973 1675);
PAINT GREEN (-7973 1675);
DISPLAY INVISIBLE (-7973 1675);
FORCEADD TAP..1
R 2
(-7975 1475);
FORCEPROP 3 LASTPIN (-7925 1475) SIG_NAME P5E_CPU0_P0_TX_BUF_DN<12>
J 0
(-7915 1485);
DISPLAY 0.659574 (-7915 1485);
PAINT MONO (-7915 1485);
DISPLAY INVISIBLE (-7915 1485);
FORCEPROP 1 LASTPIN (-7925 1475) BN 12
J 2
(-7913 1483);
DISPLAY 0.680851 (-7913 1483);
PAINT GREEN (-7913 1483);
FORCEPROP 2 LAST CDS_LIB standard
J 0
(-7975 1475);
DISPLAY INVISIBLE (-7975 1475);
FORCEPROP 1 LAST BODY_TYPE PLUMBING
J 2
(-7975 1525);
DISPLAY 0.872340 (-7975 1525);
PAINT GREEN (-7975 1525);
DISPLAY INVISIBLE (-7975 1525);
FORCEPROP 1 LAST HDL_TAP TRUE
J 2
(-8300 1350);
DISPLAY 0.872340 (-8300 1350);
DISPLAY INVISIBLE (-8300 1350);
FORCEPROP 1 LAST PATH I139
J 2
(-7973 1475);
DISPLAY 0.872340 (-7973 1475);
PAINT GREEN (-7973 1475);
DISPLAY INVISIBLE (-7973 1475);
FORCEADD TAP..1
(-7075 5700);
FORCEPROP 3 LASTPIN (-7125 5700) SIG_NAME P5E_CPU0_P0_TX_BUF_DP<14>
J 0
(-7115 5710);
DISPLAY 0.659574 (-7115 5710);
PAINT MONO (-7115 5710);
DISPLAY INVISIBLE (-7115 5710);
FORCEPROP 1 LASTPIN (-7125 5700) BN 14
J 0
(-7137 5708);
DISPLAY 0.680851 (-7137 5708);
PAINT GREEN (-7137 5708);
FORCEPROP 2 LAST CDS_LIB standard
J 0
(-7075 5700);
DISPLAY INVISIBLE (-7075 5700);
FORCEPROP 1 LAST BODY_TYPE PLUMBING
J 0
(-7075 5750);
DISPLAY 0.872340 (-7075 5750);
PAINT GREEN (-7075 5750);
DISPLAY INVISIBLE (-7075 5750);
FORCEPROP 1 LAST HDL_TAP TRUE
J 0
(-6750 5575);
DISPLAY 0.872340 (-6750 5575);
DISPLAY INVISIBLE (-6750 5575);
FORCEPROP 1 LAST PATH I14
J 0
(-7077 5700);
DISPLAY 0.872340 (-7077 5700);
PAINT GREEN (-7077 5700);
DISPLAY INVISIBLE (-7077 5700);
FORCEADD TAP..1
R 2
(-7975 1275);
FORCEPROP 3 LASTPIN (-7925 1275) SIG_NAME P5E_CPU0_P0_TX_BUF_DN<13>
J 0
(-7915 1285);
DISPLAY 0.659574 (-7915 1285);
PAINT MONO (-7915 1285);
DISPLAY INVISIBLE (-7915 1285);
FORCEPROP 1 LASTPIN (-7925 1275) BN 13
J 2
(-7913 1283);
DISPLAY 0.680851 (-7913 1283);
PAINT GREEN (-7913 1283);
FORCEPROP 2 LAST CDS_LIB standard
J 0
(-7975 1275);
DISPLAY INVISIBLE (-7975 1275);
FORCEPROP 1 LAST BODY_TYPE PLUMBING
J 2
(-7975 1325);
DISPLAY 0.872340 (-7975 1325);
PAINT GREEN (-7975 1325);
DISPLAY INVISIBLE (-7975 1325);
FORCEPROP 1 LAST HDL_TAP TRUE
J 2
(-8300 1150);
DISPLAY 0.872340 (-8300 1150);
DISPLAY INVISIBLE (-8300 1150);
FORCEPROP 1 LAST PATH I140
J 2
(-7973 1275);
DISPLAY 0.872340 (-7973 1275);
PAINT GREEN (-7973 1275);
DISPLAY INVISIBLE (-7973 1275);
FORCEADD TAP..1
R 2
(-7975 1075);
FORCEPROP 3 LASTPIN (-7925 1075) SIG_NAME P5E_CPU0_P0_TX_BUF_DN<14>
J 0
(-7915 1085);
DISPLAY 0.659574 (-7915 1085);
PAINT MONO (-7915 1085);
DISPLAY INVISIBLE (-7915 1085);
FORCEPROP 1 LASTPIN (-7925 1075) BN 14
J 2
(-7913 1083);
DISPLAY 0.680851 (-7913 1083);
PAINT GREEN (-7913 1083);
FORCEPROP 2 LAST CDS_LIB standard
J 0
(-7975 1075);
DISPLAY INVISIBLE (-7975 1075);
FORCEPROP 1 LAST BODY_TYPE PLUMBING
J 2
(-7975 1125);
DISPLAY 0.872340 (-7975 1125);
PAINT GREEN (-7975 1125);
DISPLAY INVISIBLE (-7975 1125);
FORCEPROP 1 LAST HDL_TAP TRUE
J 2
(-8300 950);
DISPLAY 0.872340 (-8300 950);
DISPLAY INVISIBLE (-8300 950);
FORCEPROP 1 LAST PATH I141
J 2
(-7973 1075);
DISPLAY 0.872340 (-7973 1075);
PAINT GREEN (-7973 1075);
DISPLAY INVISIBLE (-7973 1075);
FORCEADD TAP..1
R 2
(-7975 875);
FORCEPROP 3 LASTPIN (-7925 875) SIG_NAME P5E_CPU0_P0_TX_BUF_DN<15>
J 0
(-7915 885);
DISPLAY 0.659574 (-7915 885);
PAINT MONO (-7915 885);
DISPLAY INVISIBLE (-7915 885);
FORCEPROP 1 LASTPIN (-7925 875) BN 15
J 2
(-7913 883);
DISPLAY 0.680851 (-7913 883);
PAINT GREEN (-7913 883);
FORCEPROP 2 LAST CDS_LIB standard
J 0
(-7975 875);
DISPLAY INVISIBLE (-7975 875);
FORCEPROP 1 LAST BODY_TYPE PLUMBING
J 2
(-7975 925);
DISPLAY 0.872340 (-7975 925);
PAINT GREEN (-7975 925);
DISPLAY INVISIBLE (-7975 925);
FORCEPROP 1 LAST HDL_TAP TRUE
J 2
(-8300 750);
DISPLAY 0.872340 (-8300 750);
DISPLAY INVISIBLE (-8300 750);
FORCEPROP 1 LAST PATH I142
J 2
(-7973 875);
DISPLAY 0.872340 (-7973 875);
PAINT GREEN (-7973 875);
DISPLAY INVISIBLE (-7973 875);
FORCEADD OFFPAGE..1
(-8925 2300);
FORCEPROP 2 LAST $XR0 276 
J 0
(-9207 2300);
DISPLAY 0.638298 (-9207 2300);
PAINT MONO (-9207 2300);
FORCEPROP 2 LAST CDS_LIB standard
J 0
(-8925 2300);
DISPLAY INVISIBLE (-8925 2300);
FORCEPROP 1 LAST OFFPAGE TRUE
J 0
(-8600 2175);
DISPLAY 0.872340 (-8600 2175);
DISPLAY INVISIBLE (-8600 2175);
FORCEPROP 1 LAST COMMENT_BODY TRUE
J 0
(-8800 2200);
DISPLAY 0.872340 (-8800 2200);
PAINT GREEN (-8800 2200);
DISPLAY INVISIBLE (-8800 2200);
FORCEPROP 2 LAST PATH I143
J 0
(-9175 2350);
DISPLAY 0.680851 (-9175 2350);
DISPLAY INVISIBLE (-9175 2350);
FORCEADD OFFPAGE..1
(-8925 2350);
FORCEPROP 2 LAST $XR0 276 
J 0
(-9207 2350);
DISPLAY 0.638298 (-9207 2350);
PAINT MONO (-9207 2350);
FORCEPROP 2 LAST CDS_LIB standard
J 0
(-8925 2350);
DISPLAY INVISIBLE (-8925 2350);
FORCEPROP 1 LAST OFFPAGE TRUE
J 0
(-8600 2225);
DISPLAY 0.872340 (-8600 2225);
DISPLAY INVISIBLE (-8600 2225);
FORCEPROP 1 LAST COMMENT_BODY TRUE
J 0
(-8800 2250);
DISPLAY 0.872340 (-8800 2250);
PAINT GREEN (-8800 2250);
DISPLAY INVISIBLE (-8800 2250);
FORCEPROP 2 LAST PATH I144
J 0
(-9175 2400);
DISPLAY 0.680851 (-9175 2400);
DISPLAY INVISIBLE (-9175 2400);
FORCEADD TAP..1
(-7075 6050);
FORCEPROP 3 LASTPIN (-7125 6050) SIG_NAME P5E_CPU0_P0_TX_BUF_DP<15>
J 0
(-7115 6060);
DISPLAY 0.659574 (-7115 6060);
PAINT MONO (-7115 6060);
DISPLAY INVISIBLE (-7115 6060);
FORCEPROP 1 LASTPIN (-7125 6050) BN 15
J 0
(-7137 6058);
DISPLAY 0.680851 (-7137 6058);
PAINT GREEN (-7137 6058);
FORCEPROP 2 LAST CDS_LIB standard
J 0
(-7075 6050);
DISPLAY INVISIBLE (-7075 6050);
FORCEPROP 1 LAST BODY_TYPE PLUMBING
J 0
(-7075 6100);
DISPLAY 0.872340 (-7075 6100);
PAINT GREEN (-7075 6100);
DISPLAY INVISIBLE (-7075 6100);
FORCEPROP 1 LAST HDL_TAP TRUE
J 0
(-6750 5925);
DISPLAY 0.872340 (-6750 5925);
DISPLAY INVISIBLE (-6750 5925);
FORCEPROP 1 LAST PATH I15
J 0
(-7077 6050);
DISPLAY 0.872340 (-7077 6050);
PAINT GREEN (-7077 6050);
DISPLAY INVISIBLE (-7077 6050);
FORCEADD TAP..1
(-6875 5950);
FORCEPROP 3 LASTPIN (-6925 5950) SIG_NAME P5E_CPU0_P0_TX_BUF_DN<15>
J 0
(-6915 5960);
DISPLAY 0.659574 (-6915 5960);
PAINT MONO (-6915 5960);
DISPLAY INVISIBLE (-6915 5960);
FORCEPROP 1 LASTPIN (-6925 5950) BN 15
J 0
(-6937 5958);
DISPLAY 0.680851 (-6937 5958);
PAINT GREEN (-6937 5958);
FORCEPROP 2 LAST CDS_LIB standard
J 0
(-6875 5950);
DISPLAY INVISIBLE (-6875 5950);
FORCEPROP 1 LAST BODY_TYPE PLUMBING
J 0
(-6875 6000);
DISPLAY 0.872340 (-6875 6000);
PAINT GREEN (-6875 6000);
DISPLAY INVISIBLE (-6875 6000);
FORCEPROP 1 LAST HDL_TAP TRUE
J 0
(-6550 5825);
DISPLAY 0.872340 (-6550 5825);
DISPLAY INVISIBLE (-6550 5825);
FORCEPROP 1 LAST PATH I16
J 0
(-6877 5950);
DISPLAY 0.872340 (-6877 5950);
PAINT GREEN (-6877 5950);
DISPLAY INVISIBLE (-6877 5950);
FORCEADD TAP..1
(-7075 5000);
FORCEPROP 3 LASTPIN (-7125 5000) SIG_NAME P5E_CPU0_P0_TX_BUF_DP<12>
J 0
(-7115 5010);
DISPLAY 0.659574 (-7115 5010);
PAINT MONO (-7115 5010);
DISPLAY INVISIBLE (-7115 5010);
FORCEPROP 1 LASTPIN (-7125 5000) BN 12
J 0
(-7137 5008);
DISPLAY 0.680851 (-7137 5008);
PAINT GREEN (-7137 5008);
FORCEPROP 2 LAST CDS_LIB standard
J 0
(-7075 5000);
DISPLAY INVISIBLE (-7075 5000);
FORCEPROP 1 LAST BODY_TYPE PLUMBING
J 0
(-7075 5050);
DISPLAY 0.872340 (-7075 5050);
PAINT GREEN (-7075 5050);
DISPLAY INVISIBLE (-7075 5050);
FORCEPROP 1 LAST HDL_TAP TRUE
J 0
(-6750 4875);
DISPLAY 0.872340 (-6750 4875);
DISPLAY INVISIBLE (-6750 4875);
FORCEPROP 1 LAST PATH I19
J 0
(-7077 5000);
DISPLAY 0.872340 (-7077 5000);
PAINT GREEN (-7077 5000);
DISPLAY INVISIBLE (-7077 5000);
FORCEADD PT5161LRS..11
(-2625 4775);
FORCEPROP 1 LAST LOCATION U6010
J 0
(-2975 6400);
DISPLAY 0.723404 (-2975 6400);
PAINT GREEN (-2975 6400);
FORCEPROP 0 LAST $SEC 11
J 0
(-2975 6550);
DISPLAY 0.680851 (-2975 6550);
PAINT MONO (-2975 6550);
DISPLAY INVISIBLE (-2975 6550);
FORCEPROP 0 LAST CDS_SEC 11
J 0
(-2975 6550);
DISPLAY 0.680851 (-2975 6550);
DISPLAY INVISIBLE (-2975 6550);
FORCEPROP 0 LASTPIN (-2175 5925) $PN CK10
J 0
(-2165 5935);
DISPLAY 0.680851 (-2165 5935);
PAINT MONO (-2165 5935);
FORCEPROP 0 LASTPIN (-2175 5575) $PN CU10
J 0
(-2165 5585);
DISPLAY 0.680851 (-2165 5585);
PAINT MONO (-2165 5585);
FORCEPROP 0 LASTPIN (-2175 5225) $PN DD10
J 0
(-2165 5235);
DISPLAY 0.680851 (-2165 5235);
PAINT MONO (-2165 5235);
FORCEPROP 0 LASTPIN (-2175 4875) $PN DL10
J 0
(-2165 4885);
DISPLAY 0.680851 (-2165 4885);
PAINT MONO (-2165 4885);
FORCEPROP 0 LASTPIN (-2175 4525) $PN DV10
J 0
(-2165 4535);
DISPLAY 0.680851 (-2165 4535);
PAINT MONO (-2165 4535);
FORCEPROP 0 LASTPIN (-2175 4175) $PN EE10
J 0
(-2165 4185);
DISPLAY 0.680851 (-2165 4185);
PAINT MONO (-2165 4185);
FORCEPROP 0 LASTPIN (-2175 3825) $PN EM10
J 0
(-2165 3835);
DISPLAY 0.680851 (-2165 3835);
PAINT MONO (-2165 3835);
FORCEPROP 0 LASTPIN (-2175 3475) $PN EW10
J 0
(-2165 3485);
DISPLAY 0.680851 (-2165 3485);
PAINT MONO (-2165 3485);
FORCEPROP 0 LASTPIN (-2175 6025) $PN CH7
J 0
(-2165 6035);
DISPLAY 0.680851 (-2165 6035);
PAINT MONO (-2165 6035);
FORCEPROP 0 LASTPIN (-2175 5675) $PN CR7
J 0
(-2165 5685);
DISPLAY 0.680851 (-2165 5685);
PAINT MONO (-2165 5685);
FORCEPROP 0 LASTPIN (-2175 5325) $PN DB7
J 0
(-2165 5335);
DISPLAY 0.680851 (-2165 5335);
PAINT MONO (-2165 5335);
FORCEPROP 0 LASTPIN (-2175 4975) $PN DJ7
J 0
(-2165 4985);
DISPLAY 0.680851 (-2165 4985);
PAINT MONO (-2165 4985);
FORCEPROP 0 LASTPIN (-2175 4625) $PN DT7
J 0
(-2165 4635);
DISPLAY 0.680851 (-2165 4635);
PAINT MONO (-2165 4635);
FORCEPROP 0 LASTPIN (-2175 4275) $PN EC7
J 0
(-2165 4285);
DISPLAY 0.680851 (-2165 4285);
PAINT MONO (-2165 4285);
FORCEPROP 0 LASTPIN (-2175 3925) $PN EK7
J 0
(-2165 3935);
DISPLAY 0.680851 (-2165 3935);
PAINT MONO (-2165 3935);
FORCEPROP 0 LASTPIN (-2175 3575) $PN EU7
J 0
(-2165 3585);
DISPLAY 0.680851 (-2165 3585);
PAINT MONO (-2165 3585);
FORCEPROP 1 LAST MATERIAL IC
J 0
(-2975 6250);
DISPLAY 0.723404 (-2975 6250);
PAINT GREEN (-2975 6250);
FORCEPROP 2 LAST VALUE PT5161LRS
J 0
(-2975 6450);
DISPLAY 0.680851 (-2975 6450);
FORCEPROP 2 LAST PART_TYPE SMLF
J 0
(-2975 6500);
DISPLAY 0.680851 (-2975 6500);
FORCEPROP 1 LAST NEEDS_NO_SIZE TRUE
J 0
(-2625 4775);
DISPLAY 0.723404 (-2625 4775);
PAINT GREEN (-2625 4775);
DISPLAY INVISIBLE (-2625 4775);
FORCEPROP 1 LAST CDS_LMAN_SYM_OUTLINE -350,1450,300,-1400
J 0
(-2625 4775);
DISPLAY 0.468085 (-2625 4775);
PAINT GREEN (-2625 4775);
DISPLAY INVISIBLE (-2625 4775);
FORCEPROP 2 LAST CDS_LIB pure_quanta
J 0
(-2625 4775);
DISPLAY INVISIBLE (-2625 4775);
FORCEPROP 1 LAST PATH I2
J 0
(-2625 4775);
DISPLAY 0.723404 (-2625 4775);
PAINT GREEN (-2625 4775);
DISPLAY INVISIBLE (-2625 4775);
FORCEPROP 1 LAST PART_NUMBER AJ051610U03
J 0
(-2975 6325);
DISPLAY 0.723404 (-2975 6325);
PAINT GREEN (-2975 6325);
DISPLAY INVISIBLE (-2975 6325);
FORCEADD TAP..1
(-6875 5600);
FORCEPROP 3 LASTPIN (-6925 5600) SIG_NAME P5E_CPU0_P0_TX_BUF_DN<14>
J 0
(-6915 5610);
DISPLAY 0.659574 (-6915 5610);
PAINT MONO (-6915 5610);
DISPLAY INVISIBLE (-6915 5610);
FORCEPROP 1 LASTPIN (-6925 5600) BN 14
J 0
(-6937 5608);
DISPLAY 0.680851 (-6937 5608);
PAINT GREEN (-6937 5608);
FORCEPROP 2 LAST CDS_LIB standard
J 0
(-6875 5600);
DISPLAY INVISIBLE (-6875 5600);
FORCEPROP 1 LAST BODY_TYPE PLUMBING
J 0
(-6875 5650);
DISPLAY 0.872340 (-6875 5650);
PAINT GREEN (-6875 5650);
DISPLAY INVISIBLE (-6875 5650);
FORCEPROP 1 LAST HDL_TAP TRUE
J 0
(-6550 5475);
DISPLAY 0.872340 (-6550 5475);
DISPLAY INVISIBLE (-6550 5475);
FORCEPROP 1 LAST PATH I20
J 0
(-6877 5600);
DISPLAY 0.872340 (-6877 5600);
PAINT GREEN (-6877 5600);
DISPLAY INVISIBLE (-6877 5600);
FORCEADD OFFPAGE..5
R 2
(-5875 6075);
FORCEPROP 2 LAST $XR0 276 
J 0
(-5686 6075);
DISPLAY 0.638298 (-5686 6075);
PAINT MONO (-5686 6075);
FORCEPROP 2 LAST CDS_LIB standard
J 0
(-5875 6075);
DISPLAY INVISIBLE (-5875 6075);
FORCEPROP 1 LAST OFFPAGE TRUE
J 2
(-6200 5950);
DISPLAY 0.872340 (-6200 5950);
PAINT GREEN (-6200 5950);
DISPLAY INVISIBLE (-6200 5950);
FORCEPROP 1 LAST COMMENT_BODY TRUE
J 2
(-5975 6000);
DISPLAY 0.872340 (-5975 6000);
PAINT GREEN (-5975 6000);
DISPLAY INVISIBLE (-5975 6000);
FORCEPROP 2 LAST PATH I21
J 0
(-5700 6150);
DISPLAY 0.680851 (-5700 6150);
DISPLAY INVISIBLE (-5700 6150);
FORCEADD OFFPAGE..5
R 2
(-5900 5975);
FORCEPROP 2 LAST $XR0 276 
J 0
(-5711 5975);
DISPLAY 0.638298 (-5711 5975);
PAINT MONO (-5711 5975);
FORCEPROP 2 LAST CDS_LIB standard
J 0
(-5900 5975);
DISPLAY INVISIBLE (-5900 5975);
FORCEPROP 1 LAST OFFPAGE TRUE
J 2
(-6225 5850);
DISPLAY 0.872340 (-6225 5850);
PAINT GREEN (-6225 5850);
DISPLAY INVISIBLE (-6225 5850);
FORCEPROP 1 LAST COMMENT_BODY TRUE
J 2
(-6000 5900);
DISPLAY 0.872340 (-6000 5900);
PAINT GREEN (-6000 5900);
DISPLAY INVISIBLE (-6000 5900);
FORCEPROP 2 LAST PATH I22
J 0
(-5725 6050);
DISPLAY 0.680851 (-5725 6050);
DISPLAY INVISIBLE (-5725 6050);
FORCEADD OFFPAGE..5
R 2
(-700 6050);
FORCEPROP 2 LAST $XR0 276 
J 0
(-511 6050);
DISPLAY 0.638298 (-511 6050);
PAINT MONO (-511 6050);
FORCEPROP 2 LAST CDS_LIB standard
J 0
(-700 6050);
DISPLAY INVISIBLE (-700 6050);
FORCEPROP 1 LAST OFFPAGE TRUE
J 2
(-1025 5925);
DISPLAY 0.872340 (-1025 5925);
PAINT GREEN (-1025 5925);
DISPLAY INVISIBLE (-1025 5925);
FORCEPROP 1 LAST COMMENT_BODY TRUE
J 2
(-800 5975);
DISPLAY 0.872340 (-800 5975);
PAINT GREEN (-800 5975);
DISPLAY INVISIBLE (-800 5975);
FORCEPROP 2 LAST PATH I23
J 0
(-525 6125);
DISPLAY 0.680851 (-525 6125);
DISPLAY INVISIBLE (-525 6125);
FORCEADD OFFPAGE..5
R 2
(-725 5950);
FORCEPROP 2 LAST $XR0 276 
J 0
(-536 5950);
DISPLAY 0.638298 (-536 5950);
PAINT MONO (-536 5950);
FORCEPROP 2 LAST CDS_LIB standard
J 0
(-725 5950);
DISPLAY INVISIBLE (-725 5950);
FORCEPROP 1 LAST OFFPAGE TRUE
J 2
(-1050 5825);
DISPLAY 0.872340 (-1050 5825);
PAINT GREEN (-1050 5825);
DISPLAY INVISIBLE (-1050 5825);
FORCEPROP 1 LAST COMMENT_BODY TRUE
J 2
(-825 5875);
DISPLAY 0.872340 (-825 5875);
PAINT GREEN (-825 5875);
DISPLAY INVISIBLE (-825 5875);
FORCEPROP 2 LAST PATH I24
J 0
(-550 6025);
DISPLAY 0.680851 (-550 6025);
DISPLAY INVISIBLE (-550 6025);
FORCEADD TAP..1
(-1700 5925);
FORCEPROP 3 LASTPIN (-1750 5925) SIG_NAME P5E_CPU0_P0_TX_BUF_DN<7>
J 0
(-1740 5935);
DISPLAY 0.659574 (-1740 5935);
PAINT MONO (-1740 5935);
DISPLAY INVISIBLE (-1740 5935);
FORCEPROP 1 LASTPIN (-1750 5925) BN 7
J 0
(-1762 5933);
DISPLAY 0.680851 (-1762 5933);
PAINT GREEN (-1762 5933);
FORCEPROP 2 LAST CDS_LIB standard
J 0
(-1700 5925);
DISPLAY INVISIBLE (-1700 5925);
FORCEPROP 1 LAST BODY_TYPE PLUMBING
J 0
(-1700 5975);
DISPLAY 0.872340 (-1700 5975);
PAINT GREEN (-1700 5975);
DISPLAY INVISIBLE (-1700 5975);
FORCEPROP 1 LAST HDL_TAP TRUE
J 0
(-1375 5800);
DISPLAY 0.872340 (-1375 5800);
DISPLAY INVISIBLE (-1375 5800);
FORCEPROP 1 LAST PATH I25
J 0
(-1702 5925);
DISPLAY 0.872340 (-1702 5925);
PAINT GREEN (-1702 5925);
DISPLAY INVISIBLE (-1702 5925);
FORCEADD TAP..1
(-1900 6025);
FORCEPROP 3 LASTPIN (-1950 6025) SIG_NAME P5E_CPU0_P0_TX_BUF_DP<7>
J 0
(-1940 6035);
DISPLAY 0.659574 (-1940 6035);
PAINT MONO (-1940 6035);
DISPLAY INVISIBLE (-1940 6035);
FORCEPROP 1 LASTPIN (-1950 6025) BN 7
J 0
(-1962 6033);
DISPLAY 0.680851 (-1962 6033);
PAINT GREEN (-1962 6033);
FORCEPROP 2 LAST CDS_LIB standard
J 0
(-1900 6025);
DISPLAY INVISIBLE (-1900 6025);
FORCEPROP 1 LAST BODY_TYPE PLUMBING
J 0
(-1900 6075);
DISPLAY 0.872340 (-1900 6075);
PAINT GREEN (-1900 6075);
DISPLAY INVISIBLE (-1900 6075);
FORCEPROP 1 LAST HDL_TAP TRUE
J 0
(-1575 5900);
DISPLAY 0.872340 (-1575 5900);
DISPLAY INVISIBLE (-1575 5900);
FORCEPROP 1 LAST PATH I26
J 0
(-1902 6025);
DISPLAY 0.872340 (-1902 6025);
PAINT GREEN (-1902 6025);
DISPLAY INVISIBLE (-1902 6025);
FORCEADD TAP..1
(-1900 5675);
FORCEPROP 3 LASTPIN (-1950 5675) SIG_NAME P5E_CPU0_P0_TX_BUF_DP<6>
J 0
(-1940 5685);
DISPLAY 0.659574 (-1940 5685);
PAINT MONO (-1940 5685);
DISPLAY INVISIBLE (-1940 5685);
FORCEPROP 1 LASTPIN (-1950 5675) BN 6
J 0
(-1962 5683);
DISPLAY 0.680851 (-1962 5683);
PAINT GREEN (-1962 5683);
FORCEPROP 2 LAST CDS_LIB standard
J 0
(-1900 5675);
DISPLAY INVISIBLE (-1900 5675);
FORCEPROP 1 LAST BODY_TYPE PLUMBING
J 0
(-1900 5725);
DISPLAY 0.872340 (-1900 5725);
PAINT GREEN (-1900 5725);
DISPLAY INVISIBLE (-1900 5725);
FORCEPROP 1 LAST HDL_TAP TRUE
J 0
(-1575 5550);
DISPLAY 0.872340 (-1575 5550);
DISPLAY INVISIBLE (-1575 5550);
FORCEPROP 1 LAST PATH I27
J 0
(-1902 5675);
DISPLAY 0.872340 (-1902 5675);
PAINT GREEN (-1902 5675);
DISPLAY INVISIBLE (-1902 5675);
FORCEADD TAP..1
(-1700 5575);
FORCEPROP 3 LASTPIN (-1750 5575) SIG_NAME P5E_CPU0_P0_TX_BUF_DN<6>
J 0
(-1740 5585);
DISPLAY 0.659574 (-1740 5585);
PAINT MONO (-1740 5585);
DISPLAY INVISIBLE (-1740 5585);
FORCEPROP 1 LASTPIN (-1750 5575) BN 6
J 0
(-1762 5583);
DISPLAY 0.680851 (-1762 5583);
PAINT GREEN (-1762 5583);
FORCEPROP 2 LAST CDS_LIB standard
J 0
(-1700 5575);
DISPLAY INVISIBLE (-1700 5575);
FORCEPROP 1 LAST BODY_TYPE PLUMBING
J 0
(-1700 5625);
DISPLAY 0.872340 (-1700 5625);
PAINT GREEN (-1700 5625);
DISPLAY INVISIBLE (-1700 5625);
FORCEPROP 1 LAST HDL_TAP TRUE
J 0
(-1375 5450);
DISPLAY 0.872340 (-1375 5450);
DISPLAY INVISIBLE (-1375 5450);
FORCEPROP 1 LAST PATH I28
J 0
(-1702 5575);
DISPLAY 0.872340 (-1702 5575);
PAINT GREEN (-1702 5575);
DISPLAY INVISIBLE (-1702 5575);
FORCEADD TAP..1
(-1900 5325);
FORCEPROP 3 LASTPIN (-1950 5325) SIG_NAME P5E_CPU0_P0_TX_BUF_DP<5>
J 0
(-1940 5335);
DISPLAY 0.659574 (-1940 5335);
PAINT MONO (-1940 5335);
DISPLAY INVISIBLE (-1940 5335);
FORCEPROP 1 LASTPIN (-1950 5325) BN 5
J 0
(-1962 5333);
DISPLAY 0.680851 (-1962 5333);
PAINT GREEN (-1962 5333);
FORCEPROP 2 LAST CDS_LIB standard
J 0
(-1900 5325);
DISPLAY INVISIBLE (-1900 5325);
FORCEPROP 1 LAST BODY_TYPE PLUMBING
J 0
(-1900 5375);
DISPLAY 0.872340 (-1900 5375);
PAINT GREEN (-1900 5375);
DISPLAY INVISIBLE (-1900 5375);
FORCEPROP 1 LAST HDL_TAP TRUE
J 0
(-1575 5200);
DISPLAY 0.872340 (-1575 5200);
DISPLAY INVISIBLE (-1575 5200);
FORCEPROP 1 LAST PATH I29
J 0
(-1902 5325);
DISPLAY 0.872340 (-1902 5325);
PAINT GREEN (-1902 5325);
DISPLAY INVISIBLE (-1902 5325);
FORCEADD TAP..1
(-6875 3500);
FORCEPROP 3 LASTPIN (-6925 3500) SIG_NAME P5E_CPU0_P0_TX_BUF_DN<8>
J 0
(-6915 3510);
DISPLAY 0.659574 (-6915 3510);
PAINT MONO (-6915 3510);
DISPLAY INVISIBLE (-6915 3510);
FORCEPROP 1 LASTPIN (-6925 3500) BN 8
J 0
(-6937 3508);
DISPLAY 0.680851 (-6937 3508);
PAINT GREEN (-6937 3508);
FORCEPROP 2 LAST CDS_LIB standard
J 0
(-6875 3500);
DISPLAY INVISIBLE (-6875 3500);
FORCEPROP 1 LAST BODY_TYPE PLUMBING
J 0
(-6875 3550);
DISPLAY 0.872340 (-6875 3550);
PAINT GREEN (-6875 3550);
DISPLAY INVISIBLE (-6875 3550);
FORCEPROP 1 LAST HDL_TAP TRUE
J 0
(-6550 3375);
DISPLAY 0.872340 (-6550 3375);
DISPLAY INVISIBLE (-6550 3375);
FORCEPROP 1 LAST PATH I3
J 0
(-6877 3500);
DISPLAY 0.872340 (-6877 3500);
PAINT GREEN (-6877 3500);
DISPLAY INVISIBLE (-6877 3500);
FORCEADD TAP..1
(-1700 5225);
FORCEPROP 3 LASTPIN (-1750 5225) SIG_NAME P5E_CPU0_P0_TX_BUF_DN<5>
J 0
(-1740 5235);
DISPLAY 0.659574 (-1740 5235);
PAINT MONO (-1740 5235);
DISPLAY INVISIBLE (-1740 5235);
FORCEPROP 1 LASTPIN (-1750 5225) BN 5
J 0
(-1762 5233);
DISPLAY 0.680851 (-1762 5233);
PAINT GREEN (-1762 5233);
FORCEPROP 2 LAST CDS_LIB standard
J 0
(-1700 5225);
DISPLAY INVISIBLE (-1700 5225);
FORCEPROP 1 LAST BODY_TYPE PLUMBING
J 0
(-1700 5275);
DISPLAY 0.872340 (-1700 5275);
PAINT GREEN (-1700 5275);
DISPLAY INVISIBLE (-1700 5275);
FORCEPROP 1 LAST HDL_TAP TRUE
J 0
(-1375 5100);
DISPLAY 0.872340 (-1375 5100);
DISPLAY INVISIBLE (-1375 5100);
FORCEPROP 1 LAST PATH I30
J 0
(-1702 5225);
DISPLAY 0.872340 (-1702 5225);
PAINT GREEN (-1702 5225);
DISPLAY INVISIBLE (-1702 5225);
FORCEADD TAP..1
(-1900 4975);
FORCEPROP 3 LASTPIN (-1950 4975) SIG_NAME P5E_CPU0_P0_TX_BUF_DP<4>
J 0
(-1940 4985);
DISPLAY 0.659574 (-1940 4985);
PAINT MONO (-1940 4985);
DISPLAY INVISIBLE (-1940 4985);
FORCEPROP 1 LASTPIN (-1950 4975) BN 4
J 0
(-1962 4983);
DISPLAY 0.680851 (-1962 4983);
PAINT GREEN (-1962 4983);
FORCEPROP 2 LAST CDS_LIB standard
J 0
(-1900 4975);
DISPLAY INVISIBLE (-1900 4975);
FORCEPROP 1 LAST BODY_TYPE PLUMBING
J 0
(-1900 5025);
DISPLAY 0.872340 (-1900 5025);
PAINT GREEN (-1900 5025);
DISPLAY INVISIBLE (-1900 5025);
FORCEPROP 1 LAST HDL_TAP TRUE
J 0
(-1575 4850);
DISPLAY 0.872340 (-1575 4850);
DISPLAY INVISIBLE (-1575 4850);
FORCEPROP 1 LAST PATH I31
J 0
(-1902 4975);
DISPLAY 0.872340 (-1902 4975);
PAINT GREEN (-1902 4975);
DISPLAY INVISIBLE (-1902 4975);
FORCEADD TAP..1
(-1700 4875);
FORCEPROP 3 LASTPIN (-1750 4875) SIG_NAME P5E_CPU0_P0_TX_BUF_DN<4>
J 0
(-1740 4885);
DISPLAY 0.659574 (-1740 4885);
PAINT MONO (-1740 4885);
DISPLAY INVISIBLE (-1740 4885);
FORCEPROP 1 LASTPIN (-1750 4875) BN 4
J 0
(-1762 4883);
DISPLAY 0.680851 (-1762 4883);
PAINT GREEN (-1762 4883);
FORCEPROP 2 LAST CDS_LIB standard
J 0
(-1700 4875);
DISPLAY INVISIBLE (-1700 4875);
FORCEPROP 1 LAST BODY_TYPE PLUMBING
J 0
(-1700 4925);
DISPLAY 0.872340 (-1700 4925);
PAINT GREEN (-1700 4925);
DISPLAY INVISIBLE (-1700 4925);
FORCEPROP 1 LAST HDL_TAP TRUE
J 0
(-1375 4750);
DISPLAY 0.872340 (-1375 4750);
DISPLAY INVISIBLE (-1375 4750);
FORCEPROP 1 LAST PATH I32
J 0
(-1702 4875);
DISPLAY 0.872340 (-1702 4875);
PAINT GREEN (-1702 4875);
DISPLAY INVISIBLE (-1702 4875);
FORCEADD TAP..1
(-1900 4625);
FORCEPROP 3 LASTPIN (-1950 4625) SIG_NAME P5E_CPU0_P0_TX_BUF_DP<3>
J 0
(-1940 4635);
DISPLAY 0.659574 (-1940 4635);
PAINT MONO (-1940 4635);
DISPLAY INVISIBLE (-1940 4635);
FORCEPROP 1 LASTPIN (-1950 4625) BN 3
J 0
(-1962 4633);
DISPLAY 0.680851 (-1962 4633);
PAINT GREEN (-1962 4633);
FORCEPROP 2 LAST CDS_LIB standard
J 0
(-1900 4625);
DISPLAY INVISIBLE (-1900 4625);
FORCEPROP 1 LAST BODY_TYPE PLUMBING
J 0
(-1900 4675);
DISPLAY 0.872340 (-1900 4675);
PAINT GREEN (-1900 4675);
DISPLAY INVISIBLE (-1900 4675);
FORCEPROP 1 LAST HDL_TAP TRUE
J 0
(-1575 4500);
DISPLAY 0.872340 (-1575 4500);
DISPLAY INVISIBLE (-1575 4500);
FORCEPROP 1 LAST PATH I33
J 0
(-1902 4625);
DISPLAY 0.872340 (-1902 4625);
PAINT GREEN (-1902 4625);
DISPLAY INVISIBLE (-1902 4625);
FORCEADD TAP..1
(-1700 4525);
FORCEPROP 3 LASTPIN (-1750 4525) SIG_NAME P5E_CPU0_P0_TX_BUF_DN<3>
J 0
(-1740 4535);
DISPLAY 0.659574 (-1740 4535);
PAINT MONO (-1740 4535);
DISPLAY INVISIBLE (-1740 4535);
FORCEPROP 1 LASTPIN (-1750 4525) BN 3
J 0
(-1762 4533);
DISPLAY 0.680851 (-1762 4533);
PAINT GREEN (-1762 4533);
FORCEPROP 2 LAST CDS_LIB standard
J 0
(-1700 4525);
DISPLAY INVISIBLE (-1700 4525);
FORCEPROP 1 LAST BODY_TYPE PLUMBING
J 0
(-1700 4575);
DISPLAY 0.872340 (-1700 4575);
PAINT GREEN (-1700 4575);
DISPLAY INVISIBLE (-1700 4575);
FORCEPROP 1 LAST HDL_TAP TRUE
J 0
(-1375 4400);
DISPLAY 0.872340 (-1375 4400);
DISPLAY INVISIBLE (-1375 4400);
FORCEPROP 1 LAST PATH I34
J 0
(-1702 4525);
DISPLAY 0.872340 (-1702 4525);
PAINT GREEN (-1702 4525);
DISPLAY INVISIBLE (-1702 4525);
FORCEADD TAP..1
(-1900 4275);
FORCEPROP 3 LASTPIN (-1950 4275) SIG_NAME P5E_CPU0_P0_TX_BUF_DP<2>
J 0
(-1940 4285);
DISPLAY 0.659574 (-1940 4285);
PAINT MONO (-1940 4285);
DISPLAY INVISIBLE (-1940 4285);
FORCEPROP 1 LASTPIN (-1950 4275) BN 2
J 0
(-1962 4283);
DISPLAY 0.680851 (-1962 4283);
PAINT GREEN (-1962 4283);
FORCEPROP 2 LAST CDS_LIB standard
J 0
(-1900 4275);
DISPLAY INVISIBLE (-1900 4275);
FORCEPROP 1 LAST BODY_TYPE PLUMBING
J 0
(-1900 4325);
DISPLAY 0.872340 (-1900 4325);
PAINT GREEN (-1900 4325);
DISPLAY INVISIBLE (-1900 4325);
FORCEPROP 1 LAST HDL_TAP TRUE
J 0
(-1575 4150);
DISPLAY 0.872340 (-1575 4150);
DISPLAY INVISIBLE (-1575 4150);
FORCEPROP 1 LAST PATH I35
J 0
(-1902 4275);
DISPLAY 0.872340 (-1902 4275);
PAINT GREEN (-1902 4275);
DISPLAY INVISIBLE (-1902 4275);
FORCEADD TAP..1
(-1700 4175);
FORCEPROP 3 LASTPIN (-1750 4175) SIG_NAME P5E_CPU0_P0_TX_BUF_DN<2>
J 0
(-1740 4185);
DISPLAY 0.659574 (-1740 4185);
PAINT MONO (-1740 4185);
DISPLAY INVISIBLE (-1740 4185);
FORCEPROP 1 LASTPIN (-1750 4175) BN 2
J 0
(-1762 4183);
DISPLAY 0.680851 (-1762 4183);
PAINT GREEN (-1762 4183);
FORCEPROP 2 LAST CDS_LIB standard
J 0
(-1700 4175);
DISPLAY INVISIBLE (-1700 4175);
FORCEPROP 1 LAST BODY_TYPE PLUMBING
J 0
(-1700 4225);
DISPLAY 0.872340 (-1700 4225);
PAINT GREEN (-1700 4225);
DISPLAY INVISIBLE (-1700 4225);
FORCEPROP 1 LAST HDL_TAP TRUE
J 0
(-1375 4050);
DISPLAY 0.872340 (-1375 4050);
DISPLAY INVISIBLE (-1375 4050);
FORCEPROP 1 LAST PATH I36
J 0
(-1702 4175);
DISPLAY 0.872340 (-1702 4175);
PAINT GREEN (-1702 4175);
DISPLAY INVISIBLE (-1702 4175);
FORCEADD TAP..1
(-1700 3825);
FORCEPROP 3 LASTPIN (-1750 3825) SIG_NAME P5E_CPU0_P0_TX_BUF_DN<1>
J 0
(-1740 3835);
DISPLAY 0.659574 (-1740 3835);
PAINT MONO (-1740 3835);
DISPLAY INVISIBLE (-1740 3835);
FORCEPROP 1 LASTPIN (-1750 3825) BN 1
J 0
(-1762 3833);
DISPLAY 0.680851 (-1762 3833);
PAINT GREEN (-1762 3833);
FORCEPROP 2 LAST CDS_LIB standard
J 0
(-1700 3825);
DISPLAY INVISIBLE (-1700 3825);
FORCEPROP 1 LAST BODY_TYPE PLUMBING
J 0
(-1700 3875);
DISPLAY 0.872340 (-1700 3875);
PAINT GREEN (-1700 3875);
DISPLAY INVISIBLE (-1700 3875);
FORCEPROP 1 LAST HDL_TAP TRUE
J 0
(-1375 3700);
DISPLAY 0.872340 (-1375 3700);
DISPLAY INVISIBLE (-1375 3700);
FORCEPROP 1 LAST PATH I37
J 0
(-1702 3825);
DISPLAY 0.872340 (-1702 3825);
PAINT GREEN (-1702 3825);
DISPLAY INVISIBLE (-1702 3825);
FORCEADD TAP..1
(-1900 3925);
FORCEPROP 3 LASTPIN (-1950 3925) SIG_NAME P5E_CPU0_P0_TX_BUF_DP<1>
J 0
(-1940 3935);
DISPLAY 0.659574 (-1940 3935);
PAINT MONO (-1940 3935);
DISPLAY INVISIBLE (-1940 3935);
FORCEPROP 1 LASTPIN (-1950 3925) BN 1
J 0
(-1962 3933);
DISPLAY 0.680851 (-1962 3933);
PAINT GREEN (-1962 3933);
FORCEPROP 2 LAST CDS_LIB standard
J 0
(-1900 3925);
DISPLAY INVISIBLE (-1900 3925);
FORCEPROP 1 LAST BODY_TYPE PLUMBING
J 0
(-1900 3975);
DISPLAY 0.872340 (-1900 3975);
PAINT GREEN (-1900 3975);
DISPLAY INVISIBLE (-1900 3975);
FORCEPROP 1 LAST HDL_TAP TRUE
J 0
(-1575 3800);
DISPLAY 0.872340 (-1575 3800);
DISPLAY INVISIBLE (-1575 3800);
FORCEPROP 1 LAST PATH I38
J 0
(-1902 3925);
DISPLAY 0.872340 (-1902 3925);
PAINT GREEN (-1902 3925);
DISPLAY INVISIBLE (-1902 3925);
FORCEADD TAP..1
(-1900 3575);
FORCEPROP 3 LASTPIN (-1950 3575) SIG_NAME P5E_CPU0_P0_TX_BUF_DP<0>
J 0
(-1940 3585);
DISPLAY 0.659574 (-1940 3585);
PAINT MONO (-1940 3585);
DISPLAY INVISIBLE (-1940 3585);
FORCEPROP 1 LASTPIN (-1950 3575) BN 0
J 0
(-1962 3583);
DISPLAY 0.680851 (-1962 3583);
PAINT GREEN (-1962 3583);
FORCEPROP 2 LAST CDS_LIB standard
J 0
(-1900 3575);
DISPLAY INVISIBLE (-1900 3575);
FORCEPROP 1 LAST BODY_TYPE PLUMBING
J 0
(-1900 3625);
DISPLAY 0.872340 (-1900 3625);
PAINT GREEN (-1900 3625);
DISPLAY INVISIBLE (-1900 3625);
FORCEPROP 1 LAST HDL_TAP TRUE
J 0
(-1575 3450);
DISPLAY 0.872340 (-1575 3450);
DISPLAY INVISIBLE (-1575 3450);
FORCEPROP 1 LAST PATH I39
J 0
(-1902 3575);
DISPLAY 0.872340 (-1902 3575);
PAINT GREEN (-1902 3575);
DISPLAY INVISIBLE (-1902 3575);
FORCEADD TAP..1
(-7075 3600);
FORCEPROP 3 LASTPIN (-7125 3600) SIG_NAME P5E_CPU0_P0_TX_BUF_DP<8>
J 0
(-7115 3610);
DISPLAY 0.659574 (-7115 3610);
PAINT MONO (-7115 3610);
DISPLAY INVISIBLE (-7115 3610);
FORCEPROP 1 LASTPIN (-7125 3600) BN 8
J 0
(-7137 3608);
DISPLAY 0.680851 (-7137 3608);
PAINT GREEN (-7137 3608);
FORCEPROP 2 LAST CDS_LIB standard
J 0
(-7075 3600);
DISPLAY INVISIBLE (-7075 3600);
FORCEPROP 1 LAST BODY_TYPE PLUMBING
J 0
(-7075 3650);
DISPLAY 0.872340 (-7075 3650);
PAINT GREEN (-7075 3650);
DISPLAY INVISIBLE (-7075 3650);
FORCEPROP 1 LAST HDL_TAP TRUE
J 0
(-6750 3475);
DISPLAY 0.872340 (-6750 3475);
DISPLAY INVISIBLE (-6750 3475);
FORCEPROP 1 LAST PATH I4
J 0
(-7077 3600);
DISPLAY 0.872340 (-7077 3600);
PAINT GREEN (-7077 3600);
DISPLAY INVISIBLE (-7077 3600);
FORCEADD TAP..1
(-1700 3475);
FORCEPROP 3 LASTPIN (-1750 3475) SIG_NAME P5E_CPU0_P0_TX_BUF_DN<0>
J 0
(-1740 3485);
DISPLAY 0.659574 (-1740 3485);
PAINT MONO (-1740 3485);
DISPLAY INVISIBLE (-1740 3485);
FORCEPROP 1 LASTPIN (-1750 3475) BN 0
J 0
(-1762 3483);
DISPLAY 0.680851 (-1762 3483);
PAINT GREEN (-1762 3483);
FORCEPROP 2 LAST CDS_LIB standard
J 0
(-1700 3475);
DISPLAY INVISIBLE (-1700 3475);
FORCEPROP 1 LAST BODY_TYPE PLUMBING
J 0
(-1700 3525);
DISPLAY 0.872340 (-1700 3525);
PAINT GREEN (-1700 3525);
DISPLAY INVISIBLE (-1700 3525);
FORCEPROP 1 LAST HDL_TAP TRUE
J 0
(-1375 3350);
DISPLAY 0.872340 (-1375 3350);
DISPLAY INVISIBLE (-1375 3350);
FORCEPROP 1 LAST PATH I40
J 0
(-1702 3475);
DISPLAY 0.872340 (-1702 3475);
PAINT GREEN (-1702 3475);
DISPLAY INVISIBLE (-1702 3475);
FORCEADD OFFPAGE..1
(-4325 2300);
FORCEPROP 2 LAST $XR0 276 
J 0
(-4607 2300);
DISPLAY 0.638298 (-4607 2300);
PAINT MONO (-4607 2300);
FORCEPROP 2 LAST CDS_LIB standard
J 0
(-4325 2300);
DISPLAY INVISIBLE (-4325 2300);
FORCEPROP 1 LAST OFFPAGE TRUE
J 0
(-4000 2175);
DISPLAY 0.872340 (-4000 2175);
DISPLAY INVISIBLE (-4000 2175);
FORCEPROP 1 LAST COMMENT_BODY TRUE
J 0
(-4200 2200);
DISPLAY 0.872340 (-4200 2200);
PAINT GREEN (-4200 2200);
DISPLAY INVISIBLE (-4200 2200);
FORCEPROP 2 LAST PATH I41
J 0
(-4575 2350);
DISPLAY 0.680851 (-4575 2350);
DISPLAY INVISIBLE (-4575 2350);
FORCEADD OFFPAGE..1
(-4325 2250);
FORCEPROP 2 LAST $XR0 276 
J 0
(-4607 2250);
DISPLAY 0.638298 (-4607 2250);
PAINT MONO (-4607 2250);
FORCEPROP 2 LAST CDS_LIB standard
J 0
(-4325 2250);
DISPLAY INVISIBLE (-4325 2250);
FORCEPROP 1 LAST OFFPAGE TRUE
J 0
(-4000 2125);
DISPLAY 0.872340 (-4000 2125);
DISPLAY INVISIBLE (-4000 2125);
FORCEPROP 1 LAST COMMENT_BODY TRUE
J 0
(-4200 2150);
DISPLAY 0.872340 (-4200 2150);
PAINT GREEN (-4200 2150);
DISPLAY INVISIBLE (-4200 2150);
FORCEPROP 2 LAST PATH I42
J 0
(-4575 2300);
DISPLAY 0.680851 (-4575 2300);
DISPLAY INVISIBLE (-4575 2300);
FORCEADD TAP..1
R 2
(-3375 825);
FORCEPROP 3 LASTPIN (-3325 825) SIG_NAME P5E_CPU0_P0_TX_BUF_DN<7>
J 0
(-3315 835);
DISPLAY 0.659574 (-3315 835);
PAINT MONO (-3315 835);
DISPLAY INVISIBLE (-3315 835);
FORCEPROP 1 LASTPIN (-3325 825) BN 7
J 2
(-3313 833);
DISPLAY 0.680851 (-3313 833);
PAINT GREEN (-3313 833);
FORCEPROP 2 LAST CDS_LIB standard
J 0
(-3375 825);
DISPLAY INVISIBLE (-3375 825);
FORCEPROP 1 LAST BODY_TYPE PLUMBING
J 2
(-3375 875);
DISPLAY 0.872340 (-3375 875);
PAINT GREEN (-3375 875);
DISPLAY INVISIBLE (-3375 875);
FORCEPROP 1 LAST HDL_TAP TRUE
J 2
(-3700 700);
DISPLAY 0.872340 (-3700 700);
DISPLAY INVISIBLE (-3700 700);
FORCEPROP 1 LAST PATH I43
J 2
(-3373 825);
DISPLAY 0.872340 (-3373 825);
PAINT GREEN (-3373 825);
DISPLAY INVISIBLE (-3373 825);
FORCEADD TAP..1
R 2
(-3375 1025);
FORCEPROP 3 LASTPIN (-3325 1025) SIG_NAME P5E_CPU0_P0_TX_BUF_DN<6>
J 0
(-3315 1035);
DISPLAY 0.659574 (-3315 1035);
PAINT MONO (-3315 1035);
DISPLAY INVISIBLE (-3315 1035);
FORCEPROP 1 LASTPIN (-3325 1025) BN 6
J 2
(-3313 1033);
DISPLAY 0.680851 (-3313 1033);
PAINT GREEN (-3313 1033);
FORCEPROP 2 LAST CDS_LIB standard
J 0
(-3375 1025);
DISPLAY INVISIBLE (-3375 1025);
FORCEPROP 1 LAST BODY_TYPE PLUMBING
J 2
(-3375 1075);
DISPLAY 0.872340 (-3375 1075);
PAINT GREEN (-3375 1075);
DISPLAY INVISIBLE (-3375 1075);
FORCEPROP 1 LAST HDL_TAP TRUE
J 2
(-3700 900);
DISPLAY 0.872340 (-3700 900);
DISPLAY INVISIBLE (-3700 900);
FORCEPROP 1 LAST PATH I44
J 2
(-3373 1025);
DISPLAY 0.872340 (-3373 1025);
PAINT GREEN (-3373 1025);
DISPLAY INVISIBLE (-3373 1025);
FORCEADD TAP..1
R 2
(-3375 1225);
FORCEPROP 3 LASTPIN (-3325 1225) SIG_NAME P5E_CPU0_P0_TX_BUF_DN<5>
J 0
(-3315 1235);
DISPLAY 0.659574 (-3315 1235);
PAINT MONO (-3315 1235);
DISPLAY INVISIBLE (-3315 1235);
FORCEPROP 1 LASTPIN (-3325 1225) BN 5
J 2
(-3313 1233);
DISPLAY 0.680851 (-3313 1233);
PAINT GREEN (-3313 1233);
FORCEPROP 2 LAST CDS_LIB standard
J 0
(-3375 1225);
DISPLAY INVISIBLE (-3375 1225);
FORCEPROP 1 LAST BODY_TYPE PLUMBING
J 2
(-3375 1275);
DISPLAY 0.872340 (-3375 1275);
PAINT GREEN (-3375 1275);
DISPLAY INVISIBLE (-3375 1275);
FORCEPROP 1 LAST HDL_TAP TRUE
J 2
(-3700 1100);
DISPLAY 0.872340 (-3700 1100);
DISPLAY INVISIBLE (-3700 1100);
FORCEPROP 1 LAST PATH I45
J 2
(-3373 1225);
DISPLAY 0.872340 (-3373 1225);
PAINT GREEN (-3373 1225);
DISPLAY INVISIBLE (-3373 1225);
FORCEADD TAP..1
R 2
(-3375 1425);
FORCEPROP 3 LASTPIN (-3325 1425) SIG_NAME P5E_CPU0_P0_TX_BUF_DN<4>
J 0
(-3315 1435);
DISPLAY 0.659574 (-3315 1435);
PAINT MONO (-3315 1435);
DISPLAY INVISIBLE (-3315 1435);
FORCEPROP 1 LASTPIN (-3325 1425) BN 4
J 2
(-3313 1433);
DISPLAY 0.680851 (-3313 1433);
PAINT GREEN (-3313 1433);
FORCEPROP 2 LAST CDS_LIB standard
J 0
(-3375 1425);
DISPLAY INVISIBLE (-3375 1425);
FORCEPROP 1 LAST BODY_TYPE PLUMBING
J 2
(-3375 1475);
DISPLAY 0.872340 (-3375 1475);
PAINT GREEN (-3375 1475);
DISPLAY INVISIBLE (-3375 1475);
FORCEPROP 1 LAST HDL_TAP TRUE
J 2
(-3700 1300);
DISPLAY 0.872340 (-3700 1300);
DISPLAY INVISIBLE (-3700 1300);
FORCEPROP 1 LAST PATH I46
J 2
(-3373 1425);
DISPLAY 0.872340 (-3373 1425);
PAINT GREEN (-3373 1425);
DISPLAY INVISIBLE (-3373 1425);
FORCEADD TAP..1
R 2
(-3125 875);
FORCEPROP 3 LASTPIN (-3075 875) SIG_NAME P5E_CPU0_P0_TX_BUF_DP<7>
J 0
(-3065 885);
DISPLAY 0.659574 (-3065 885);
PAINT MONO (-3065 885);
DISPLAY INVISIBLE (-3065 885);
FORCEPROP 1 LASTPIN (-3075 875) BN 7
J 2
(-3063 883);
DISPLAY 0.680851 (-3063 883);
PAINT GREEN (-3063 883);
FORCEPROP 2 LAST CDS_LIB standard
J 0
(-3125 875);
DISPLAY INVISIBLE (-3125 875);
FORCEPROP 1 LAST BODY_TYPE PLUMBING
J 2
(-3125 925);
DISPLAY 0.872340 (-3125 925);
PAINT GREEN (-3125 925);
DISPLAY INVISIBLE (-3125 925);
FORCEPROP 1 LAST HDL_TAP TRUE
J 2
(-3450 750);
DISPLAY 0.872340 (-3450 750);
DISPLAY INVISIBLE (-3450 750);
FORCEPROP 1 LAST PATH I47
J 2
(-3123 875);
DISPLAY 0.872340 (-3123 875);
PAINT GREEN (-3123 875);
DISPLAY INVISIBLE (-3123 875);
FORCEADD TAP..1
R 2
(-3125 1075);
FORCEPROP 3 LASTPIN (-3075 1075) SIG_NAME P5E_CPU0_P0_TX_BUF_DP<6>
J 0
(-3065 1085);
DISPLAY 0.659574 (-3065 1085);
PAINT MONO (-3065 1085);
DISPLAY INVISIBLE (-3065 1085);
FORCEPROP 1 LASTPIN (-3075 1075) BN 6
J 2
(-3063 1083);
DISPLAY 0.680851 (-3063 1083);
PAINT GREEN (-3063 1083);
FORCEPROP 2 LAST CDS_LIB standard
J 0
(-3125 1075);
DISPLAY INVISIBLE (-3125 1075);
FORCEPROP 1 LAST BODY_TYPE PLUMBING
J 2
(-3125 1125);
DISPLAY 0.872340 (-3125 1125);
PAINT GREEN (-3125 1125);
DISPLAY INVISIBLE (-3125 1125);
FORCEPROP 1 LAST HDL_TAP TRUE
J 2
(-3450 950);
DISPLAY 0.872340 (-3450 950);
DISPLAY INVISIBLE (-3450 950);
FORCEPROP 1 LAST PATH I48
J 2
(-3123 1075);
DISPLAY 0.872340 (-3123 1075);
PAINT GREEN (-3123 1075);
DISPLAY INVISIBLE (-3123 1075);
FORCEADD TAP..1
R 2
(-3125 1275);
FORCEPROP 3 LASTPIN (-3075 1275) SIG_NAME P5E_CPU0_P0_TX_BUF_DP<5>
J 0
(-3065 1285);
DISPLAY 0.659574 (-3065 1285);
PAINT MONO (-3065 1285);
DISPLAY INVISIBLE (-3065 1285);
FORCEPROP 1 LASTPIN (-3075 1275) BN 5
J 2
(-3063 1283);
DISPLAY 0.680851 (-3063 1283);
PAINT GREEN (-3063 1283);
FORCEPROP 2 LAST CDS_LIB standard
J 0
(-3125 1275);
DISPLAY INVISIBLE (-3125 1275);
FORCEPROP 1 LAST BODY_TYPE PLUMBING
J 2
(-3125 1325);
DISPLAY 0.872340 (-3125 1325);
PAINT GREEN (-3125 1325);
DISPLAY INVISIBLE (-3125 1325);
FORCEPROP 1 LAST HDL_TAP TRUE
J 2
(-3450 1150);
DISPLAY 0.872340 (-3450 1150);
DISPLAY INVISIBLE (-3450 1150);
FORCEPROP 1 LAST PATH I49
J 2
(-3123 1275);
DISPLAY 0.872340 (-3123 1275);
PAINT GREEN (-3123 1275);
DISPLAY INVISIBLE (-3123 1275);
FORCEADD TAP..1
(-7075 3950);
FORCEPROP 3 LASTPIN (-7125 3950) SIG_NAME P5E_CPU0_P0_TX_BUF_DP<9>
J 0
(-7115 3960);
DISPLAY 0.659574 (-7115 3960);
PAINT MONO (-7115 3960);
DISPLAY INVISIBLE (-7115 3960);
FORCEPROP 1 LASTPIN (-7125 3950) BN 9
J 0
(-7137 3958);
DISPLAY 0.680851 (-7137 3958);
PAINT GREEN (-7137 3958);
FORCEPROP 2 LAST CDS_LIB standard
J 0
(-7075 3950);
DISPLAY INVISIBLE (-7075 3950);
FORCEPROP 1 LAST BODY_TYPE PLUMBING
J 0
(-7075 4000);
DISPLAY 0.872340 (-7075 4000);
PAINT GREEN (-7075 4000);
DISPLAY INVISIBLE (-7075 4000);
FORCEPROP 1 LAST HDL_TAP TRUE
J 0
(-6750 3825);
DISPLAY 0.872340 (-6750 3825);
DISPLAY INVISIBLE (-6750 3825);
FORCEPROP 1 LAST PATH I5
J 0
(-7077 3950);
DISPLAY 0.872340 (-7077 3950);
PAINT GREEN (-7077 3950);
DISPLAY INVISIBLE (-7077 3950);
FORCEADD TAP..1
R 2
(-3125 1475);
FORCEPROP 3 LASTPIN (-3075 1475) SIG_NAME P5E_CPU0_P0_TX_BUF_DP<4>
J 0
(-3065 1485);
DISPLAY 0.659574 (-3065 1485);
PAINT MONO (-3065 1485);
DISPLAY INVISIBLE (-3065 1485);
FORCEPROP 1 LASTPIN (-3075 1475) BN 4
J 2
(-3063 1483);
DISPLAY 0.680851 (-3063 1483);
PAINT GREEN (-3063 1483);
FORCEPROP 2 LAST CDS_LIB standard
J 0
(-3125 1475);
DISPLAY INVISIBLE (-3125 1475);
FORCEPROP 1 LAST BODY_TYPE PLUMBING
J 2
(-3125 1525);
DISPLAY 0.872340 (-3125 1525);
PAINT GREEN (-3125 1525);
DISPLAY INVISIBLE (-3125 1525);
FORCEPROP 1 LAST HDL_TAP TRUE
J 2
(-3450 1350);
DISPLAY 0.872340 (-3450 1350);
DISPLAY INVISIBLE (-3450 1350);
FORCEPROP 1 LAST PATH I50
J 2
(-3123 1475);
DISPLAY 0.872340 (-3123 1475);
PAINT GREEN (-3123 1475);
DISPLAY INVISIBLE (-3123 1475);
FORCEADD TAP..1
R 2
(-3375 1625);
FORCEPROP 3 LASTPIN (-3325 1625) SIG_NAME P5E_CPU0_P0_TX_BUF_DN<3>
J 0
(-3315 1635);
DISPLAY 0.659574 (-3315 1635);
PAINT MONO (-3315 1635);
DISPLAY INVISIBLE (-3315 1635);
FORCEPROP 1 LASTPIN (-3325 1625) BN 3
J 2
(-3313 1633);
DISPLAY 0.680851 (-3313 1633);
PAINT GREEN (-3313 1633);
FORCEPROP 2 LAST CDS_LIB standard
J 0
(-3375 1625);
DISPLAY INVISIBLE (-3375 1625);
FORCEPROP 1 LAST BODY_TYPE PLUMBING
J 2
(-3375 1675);
DISPLAY 0.872340 (-3375 1675);
PAINT GREEN (-3375 1675);
DISPLAY INVISIBLE (-3375 1675);
FORCEPROP 1 LAST HDL_TAP TRUE
J 2
(-3700 1500);
DISPLAY 0.872340 (-3700 1500);
DISPLAY INVISIBLE (-3700 1500);
FORCEPROP 1 LAST PATH I51
J 2
(-3373 1625);
DISPLAY 0.872340 (-3373 1625);
PAINT GREEN (-3373 1625);
DISPLAY INVISIBLE (-3373 1625);
FORCEADD TAP..1
R 2
(-3375 1825);
FORCEPROP 3 LASTPIN (-3325 1825) SIG_NAME P5E_CPU0_P0_TX_BUF_DN<2>
J 0
(-3315 1835);
DISPLAY 0.659574 (-3315 1835);
PAINT MONO (-3315 1835);
DISPLAY INVISIBLE (-3315 1835);
FORCEPROP 1 LASTPIN (-3325 1825) BN 2
J 2
(-3313 1833);
DISPLAY 0.680851 (-3313 1833);
PAINT GREEN (-3313 1833);
FORCEPROP 2 LAST CDS_LIB standard
J 0
(-3375 1825);
DISPLAY INVISIBLE (-3375 1825);
FORCEPROP 1 LAST BODY_TYPE PLUMBING
J 2
(-3375 1875);
DISPLAY 0.872340 (-3375 1875);
PAINT GREEN (-3375 1875);
DISPLAY INVISIBLE (-3375 1875);
FORCEPROP 1 LAST HDL_TAP TRUE
J 2
(-3700 1700);
DISPLAY 0.872340 (-3700 1700);
DISPLAY INVISIBLE (-3700 1700);
FORCEPROP 1 LAST PATH I52
J 2
(-3373 1825);
DISPLAY 0.872340 (-3373 1825);
PAINT GREEN (-3373 1825);
DISPLAY INVISIBLE (-3373 1825);
FORCEADD TAP..1
R 2
(-3375 2025);
FORCEPROP 3 LASTPIN (-3325 2025) SIG_NAME P5E_CPU0_P0_TX_BUF_DN<1>
J 0
(-3315 2035);
DISPLAY 0.659574 (-3315 2035);
PAINT MONO (-3315 2035);
DISPLAY INVISIBLE (-3315 2035);
FORCEPROP 1 LASTPIN (-3325 2025) BN 1
J 2
(-3313 2033);
DISPLAY 0.680851 (-3313 2033);
PAINT GREEN (-3313 2033);
FORCEPROP 2 LAST CDS_LIB standard
J 0
(-3375 2025);
DISPLAY INVISIBLE (-3375 2025);
FORCEPROP 1 LAST BODY_TYPE PLUMBING
J 2
(-3375 2075);
DISPLAY 0.872340 (-3375 2075);
PAINT GREEN (-3375 2075);
DISPLAY INVISIBLE (-3375 2075);
FORCEPROP 1 LAST HDL_TAP TRUE
J 2
(-3700 1900);
DISPLAY 0.872340 (-3700 1900);
DISPLAY INVISIBLE (-3700 1900);
FORCEPROP 1 LAST PATH I53
J 2
(-3373 2025);
DISPLAY 0.872340 (-3373 2025);
PAINT GREEN (-3373 2025);
DISPLAY INVISIBLE (-3373 2025);
FORCEADD TAP..1
R 2
(-3375 2225);
FORCEPROP 3 LASTPIN (-3325 2225) SIG_NAME P5E_CPU0_P0_TX_BUF_DN<0>
J 0
(-3315 2235);
DISPLAY 0.659574 (-3315 2235);
PAINT MONO (-3315 2235);
DISPLAY INVISIBLE (-3315 2235);
FORCEPROP 1 LASTPIN (-3325 2225) BN 0
J 2
(-3313 2233);
DISPLAY 0.680851 (-3313 2233);
PAINT GREEN (-3313 2233);
FORCEPROP 2 LAST CDS_LIB standard
J 0
(-3375 2225);
DISPLAY INVISIBLE (-3375 2225);
FORCEPROP 1 LAST BODY_TYPE PLUMBING
J 2
(-3375 2275);
DISPLAY 0.872340 (-3375 2275);
PAINT GREEN (-3375 2275);
DISPLAY INVISIBLE (-3375 2275);
FORCEPROP 1 LAST HDL_TAP TRUE
J 2
(-3700 2100);
DISPLAY 0.872340 (-3700 2100);
DISPLAY INVISIBLE (-3700 2100);
FORCEPROP 1 LAST PATH I54
J 2
(-3373 2225);
DISPLAY 0.872340 (-3373 2225);
PAINT GREEN (-3373 2225);
DISPLAY INVISIBLE (-3373 2225);
FORCEADD TAP..1
R 2
(-3125 1675);
FORCEPROP 3 LASTPIN (-3075 1675) SIG_NAME P5E_CPU0_P0_TX_BUF_DP<3>
J 0
(-3065 1685);
DISPLAY 0.659574 (-3065 1685);
PAINT MONO (-3065 1685);
DISPLAY INVISIBLE (-3065 1685);
FORCEPROP 1 LASTPIN (-3075 1675) BN 3
J 2
(-3063 1683);
DISPLAY 0.680851 (-3063 1683);
PAINT GREEN (-3063 1683);
FORCEPROP 2 LAST CDS_LIB standard
J 0
(-3125 1675);
DISPLAY INVISIBLE (-3125 1675);
FORCEPROP 1 LAST BODY_TYPE PLUMBING
J 2
(-3125 1725);
DISPLAY 0.872340 (-3125 1725);
PAINT GREEN (-3125 1725);
DISPLAY INVISIBLE (-3125 1725);
FORCEPROP 1 LAST HDL_TAP TRUE
J 2
(-3450 1550);
DISPLAY 0.872340 (-3450 1550);
DISPLAY INVISIBLE (-3450 1550);
FORCEPROP 1 LAST PATH I55
J 2
(-3123 1675);
DISPLAY 0.872340 (-3123 1675);
PAINT GREEN (-3123 1675);
DISPLAY INVISIBLE (-3123 1675);
FORCEADD TAP..1
R 2
(-3125 1875);
FORCEPROP 3 LASTPIN (-3075 1875) SIG_NAME P5E_CPU0_P0_TX_BUF_DP<2>
J 0
(-3065 1885);
DISPLAY 0.659574 (-3065 1885);
PAINT MONO (-3065 1885);
DISPLAY INVISIBLE (-3065 1885);
FORCEPROP 1 LASTPIN (-3075 1875) BN 2
J 2
(-3063 1883);
DISPLAY 0.680851 (-3063 1883);
PAINT GREEN (-3063 1883);
FORCEPROP 2 LAST CDS_LIB standard
J 0
(-3125 1875);
DISPLAY INVISIBLE (-3125 1875);
FORCEPROP 1 LAST BODY_TYPE PLUMBING
J 2
(-3125 1925);
DISPLAY 0.872340 (-3125 1925);
PAINT GREEN (-3125 1925);
DISPLAY INVISIBLE (-3125 1925);
FORCEPROP 1 LAST HDL_TAP TRUE
J 2
(-3450 1750);
DISPLAY 0.872340 (-3450 1750);
DISPLAY INVISIBLE (-3450 1750);
FORCEPROP 1 LAST PATH I56
J 2
(-3123 1875);
DISPLAY 0.872340 (-3123 1875);
PAINT GREEN (-3123 1875);
DISPLAY INVISIBLE (-3123 1875);
FORCEADD TAP..1
R 2
(-3125 2075);
FORCEPROP 3 LASTPIN (-3075 2075) SIG_NAME P5E_CPU0_P0_TX_BUF_DP<1>
J 0
(-3065 2085);
DISPLAY 0.659574 (-3065 2085);
PAINT MONO (-3065 2085);
DISPLAY INVISIBLE (-3065 2085);
FORCEPROP 1 LASTPIN (-3075 2075) BN 1
J 2
(-3063 2083);
DISPLAY 0.680851 (-3063 2083);
PAINT GREEN (-3063 2083);
FORCEPROP 2 LAST CDS_LIB standard
J 0
(-3125 2075);
DISPLAY INVISIBLE (-3125 2075);
FORCEPROP 1 LAST BODY_TYPE PLUMBING
J 2
(-3125 2125);
DISPLAY 0.872340 (-3125 2125);
PAINT GREEN (-3125 2125);
DISPLAY INVISIBLE (-3125 2125);
FORCEPROP 1 LAST HDL_TAP TRUE
J 2
(-3450 1950);
DISPLAY 0.872340 (-3450 1950);
DISPLAY INVISIBLE (-3450 1950);
FORCEPROP 1 LAST PATH I57
J 2
(-3123 2075);
DISPLAY 0.872340 (-3123 2075);
PAINT GREEN (-3123 2075);
DISPLAY INVISIBLE (-3123 2075);
FORCEADD TAP..1
R 2
(-3125 2275);
FORCEPROP 3 LASTPIN (-3075 2275) SIG_NAME P5E_CPU0_P0_TX_BUF_DP<0>
J 0
(-3065 2285);
DISPLAY 0.659574 (-3065 2285);
PAINT MONO (-3065 2285);
DISPLAY INVISIBLE (-3065 2285);
FORCEPROP 1 LASTPIN (-3075 2275) BN 0
J 2
(-3063 2283);
DISPLAY 0.680851 (-3063 2283);
PAINT GREEN (-3063 2283);
FORCEPROP 2 LAST CDS_LIB standard
J 0
(-3125 2275);
DISPLAY INVISIBLE (-3125 2275);
FORCEPROP 1 LAST BODY_TYPE PLUMBING
J 2
(-3125 2325);
DISPLAY 0.872340 (-3125 2325);
PAINT GREEN (-3125 2325);
DISPLAY INVISIBLE (-3125 2325);
FORCEPROP 1 LAST HDL_TAP TRUE
J 2
(-3450 2150);
DISPLAY 0.872340 (-3450 2150);
DISPLAY INVISIBLE (-3450 2150);
FORCEPROP 1 LAST PATH I58
J 2
(-3123 2275);
DISPLAY 0.872340 (-3123 2275);
PAINT GREEN (-3123 2275);
DISPLAY INVISIBLE (-3123 2275);
FORCEADD Q_CAP_DIFFBUS..2
R 2
(-2400 825);
FORCEPROP 1 LAST LOCATION C6516
J 2
(-2125 825);
DISPLAY 0.723404 (-2125 825);
PAINT GREEN (-2125 825);
FORCEPROP 2 LAST $SEC 1
J 2
(-2225 900);
DISPLAY 0.680851 (-2225 900);
PAINT MONO (-2225 900);
DISPLAY INVISIBLE (-2225 900);
FORCEPROP 2 LAST CDS_SEC 1
J 2
(-2225 900);
DISPLAY 0.680851 (-2225 900);
DISPLAY INVISIBLE (-2225 900);
FORCEPROP 2 LASTPIN (-2325 825) $PN 1
J 0
(-2315 835);
DISPLAY 0.808511 (-2315 835);
FORCEPROP 2 LASTPIN (-2475 825) $PN 2
J 2
(-2485 835);
DISPLAY 0.808511 (-2485 835);
FORCEPROP 2 LAST VALUE DIFF BUS_0.22UF
J 2
(-2550 825);
DISPLAY 0.553191 (-2550 825);
FORCEPROP 2 LAST TOLERANCE 20%
J 2
(-2475 875);
DISPLAY 0.553191 (-2475 875);
DISPLAY INVISIBLE (-2475 875);
FORCEPROP 2 LAST PACK_TYPE C0201
J 2
(-2575 875);
DISPLAY 0.553191 (-2575 875);
DISPLAY INVISIBLE (-2575 875);
FORCEPROP 1 LAST MATERIAL X6S
J 2
(-2391 904);
DISPLAY 0.574468 (-2391 904);
PAINT GREEN (-2391 904);
DISPLAY INVISIBLE (-2391 904);
FORCEPROP 2 LAST VOLTAGE 6.3V
J 2
(-2750 875);
DISPLAY 0.553191 (-2750 875);
DISPLAY INVISIBLE (-2750 875);
FORCEPROP 1 LAST PIN_NAMES_ROTATE TRUE
J 2
(-2400 825);
DISPLAY 0.489362 (-2400 825);
PAINT GREEN (-2400 825);
DISPLAY INVISIBLE (-2400 825);
FORCEPROP 2 LAST CDS_LIB pure_quanta
J 2
(-2400 825);
DISPLAY INVISIBLE (-2400 825);
FORCEPROP 1 LAST CDS_LMAN_SYM_OUTLINE -25,50,25,-50
J 2
(-2400 825);
DISPLAY 0.468085 (-2400 825);
PAINT GREEN (-2400 825);
DISPLAY INVISIBLE (-2400 825);
FORCEPROP 1 LAST PATH I59
J 2
(-2400 825);
DISPLAY 0.723404 (-2400 825);
DISPLAY INVISIBLE (-2400 825);
FORCEPROP 1 LAST PART_NUMBER SP_CH4221MEE01
J 2
(-2516 913);
DISPLAY 0.574468 (-2516 913);
PAINT GREEN (-2516 913);
DISPLAY INVISIBLE (-2516 913);
FORCEPROP 1 LAST LOCATION C6516
J 0
(-2150 900);
DISPLAY 1.021277 (-2150 900);
DISPLAY INVISIBLE (-2150 900);
FORCEADD TAP..1
(-6875 3850);
FORCEPROP 3 LASTPIN (-6925 3850) SIG_NAME P5E_CPU0_P0_TX_BUF_DN<9>
J 0
(-6915 3860);
DISPLAY 0.659574 (-6915 3860);
PAINT MONO (-6915 3860);
DISPLAY INVISIBLE (-6915 3860);
FORCEPROP 1 LASTPIN (-6925 3850) BN 9
J 0
(-6937 3858);
DISPLAY 0.680851 (-6937 3858);
PAINT GREEN (-6937 3858);
FORCEPROP 2 LAST CDS_LIB standard
J 0
(-6875 3850);
DISPLAY INVISIBLE (-6875 3850);
FORCEPROP 1 LAST BODY_TYPE PLUMBING
J 0
(-6875 3900);
DISPLAY 0.872340 (-6875 3900);
PAINT GREEN (-6875 3900);
DISPLAY INVISIBLE (-6875 3900);
FORCEPROP 1 LAST HDL_TAP TRUE
J 0
(-6550 3725);
DISPLAY 0.872340 (-6550 3725);
DISPLAY INVISIBLE (-6550 3725);
FORCEPROP 1 LAST PATH I6
J 0
(-6877 3850);
DISPLAY 0.872340 (-6877 3850);
PAINT GREEN (-6877 3850);
DISPLAY INVISIBLE (-6877 3850);
FORCEADD Q_CAP_DIFFBUS..2
R 2
(-2400 1075);
FORCEPROP 1 LAST LOCATION C6513
J 2
(-2125 1075);
DISPLAY 0.723404 (-2125 1075);
PAINT GREEN (-2125 1075);
FORCEPROP 2 LAST $SEC 1
J 2
(-2225 1150);
DISPLAY 0.680851 (-2225 1150);
PAINT MONO (-2225 1150);
DISPLAY INVISIBLE (-2225 1150);
FORCEPROP 2 LAST CDS_SEC 1
J 2
(-2225 1150);
DISPLAY 0.680851 (-2225 1150);
DISPLAY INVISIBLE (-2225 1150);
FORCEPROP 2 LASTPIN (-2325 1075) $PN 1
J 0
(-2315 1085);
DISPLAY 0.808511 (-2315 1085);
FORCEPROP 2 LASTPIN (-2475 1075) $PN 2
J 2
(-2485 1085);
DISPLAY 0.808511 (-2485 1085);
FORCEPROP 2 LAST VALUE DIFF BUS_0.22UF
J 2
(-2550 1075);
DISPLAY 0.553191 (-2550 1075);
FORCEPROP 2 LAST TOLERANCE 20%
J 2
(-2475 1125);
DISPLAY 0.553191 (-2475 1125);
DISPLAY INVISIBLE (-2475 1125);
FORCEPROP 2 LAST PACK_TYPE C0201
J 2
(-2575 1125);
DISPLAY 0.553191 (-2575 1125);
DISPLAY INVISIBLE (-2575 1125);
FORCEPROP 1 LAST MATERIAL X6S
J 2
(-2391 1154);
DISPLAY 0.574468 (-2391 1154);
PAINT GREEN (-2391 1154);
DISPLAY INVISIBLE (-2391 1154);
FORCEPROP 2 LAST VOLTAGE 6.3V
J 2
(-2750 1125);
DISPLAY 0.553191 (-2750 1125);
DISPLAY INVISIBLE (-2750 1125);
FORCEPROP 1 LAST PIN_NAMES_ROTATE TRUE
J 2
(-2400 1075);
DISPLAY 0.489362 (-2400 1075);
PAINT GREEN (-2400 1075);
DISPLAY INVISIBLE (-2400 1075);
FORCEPROP 1 LAST CDS_LMAN_SYM_OUTLINE -25,50,25,-50
J 2
(-2400 1075);
DISPLAY 0.468085 (-2400 1075);
PAINT GREEN (-2400 1075);
DISPLAY INVISIBLE (-2400 1075);
FORCEPROP 2 LAST CDS_LIB pure_quanta
J 2
(-2400 1075);
DISPLAY INVISIBLE (-2400 1075);
FORCEPROP 1 LAST PATH I60
J 2
(-2400 1075);
DISPLAY 0.723404 (-2400 1075);
DISPLAY INVISIBLE (-2400 1075);
FORCEPROP 1 LAST PART_NUMBER SP_CH4221MEE01
J 2
(-2516 1163);
DISPLAY 0.574468 (-2516 1163);
PAINT GREEN (-2516 1163);
DISPLAY INVISIBLE (-2516 1163);
FORCEPROP 1 LAST LOCATION C6513
J 0
(-2150 1150);
DISPLAY 1.021277 (-2150 1150);
DISPLAY INVISIBLE (-2150 1150);
FORCEADD Q_CAP_DIFFBUS..2
R 2
(-2400 1025);
FORCEPROP 1 LAST LOCATION C6514
J 2
(-2125 1025);
DISPLAY 0.723404 (-2125 1025);
PAINT GREEN (-2125 1025);
FORCEPROP 2 LAST $SEC 1
J 2
(-2225 1100);
DISPLAY 0.680851 (-2225 1100);
PAINT MONO (-2225 1100);
DISPLAY INVISIBLE (-2225 1100);
FORCEPROP 2 LAST CDS_SEC 1
J 2
(-2225 1100);
DISPLAY 0.680851 (-2225 1100);
DISPLAY INVISIBLE (-2225 1100);
FORCEPROP 2 LASTPIN (-2325 1025) $PN 1
J 0
(-2315 1035);
DISPLAY 0.808511 (-2315 1035);
FORCEPROP 2 LASTPIN (-2475 1025) $PN 2
J 2
(-2485 1035);
DISPLAY 0.808511 (-2485 1035);
FORCEPROP 2 LAST VALUE DIFF BUS_0.22UF
J 2
(-2550 1025);
DISPLAY 0.553191 (-2550 1025);
FORCEPROP 2 LAST TOLERANCE 20%
J 2
(-2475 1075);
DISPLAY 0.553191 (-2475 1075);
DISPLAY INVISIBLE (-2475 1075);
FORCEPROP 2 LAST PACK_TYPE C0201
J 2
(-2575 1075);
DISPLAY 0.553191 (-2575 1075);
DISPLAY INVISIBLE (-2575 1075);
FORCEPROP 1 LAST MATERIAL X6S
J 2
(-2391 1104);
DISPLAY 0.574468 (-2391 1104);
PAINT GREEN (-2391 1104);
DISPLAY INVISIBLE (-2391 1104);
FORCEPROP 2 LAST VOLTAGE 6.3V
J 2
(-2750 1075);
DISPLAY 0.553191 (-2750 1075);
DISPLAY INVISIBLE (-2750 1075);
FORCEPROP 1 LAST PIN_NAMES_ROTATE TRUE
J 2
(-2400 1025);
DISPLAY 0.489362 (-2400 1025);
PAINT GREEN (-2400 1025);
DISPLAY INVISIBLE (-2400 1025);
FORCEPROP 2 LAST CDS_LIB pure_quanta
J 2
(-2400 1025);
DISPLAY INVISIBLE (-2400 1025);
FORCEPROP 1 LAST CDS_LMAN_SYM_OUTLINE -25,50,25,-50
J 2
(-2400 1025);
DISPLAY 0.468085 (-2400 1025);
PAINT GREEN (-2400 1025);
DISPLAY INVISIBLE (-2400 1025);
FORCEPROP 1 LAST PATH I61
J 2
(-2400 1025);
DISPLAY 0.723404 (-2400 1025);
DISPLAY INVISIBLE (-2400 1025);
FORCEPROP 1 LAST PART_NUMBER SP_CH4221MEE01
J 2
(-2516 1113);
DISPLAY 0.574468 (-2516 1113);
PAINT GREEN (-2516 1113);
DISPLAY INVISIBLE (-2516 1113);
FORCEPROP 1 LAST LOCATION C6514
J 0
(-2150 1100);
DISPLAY 1.021277 (-2150 1100);
DISPLAY INVISIBLE (-2150 1100);
FORCEADD Q_CAP_DIFFBUS..2
R 2
(-2400 875);
FORCEPROP 1 LAST LOCATION C6515
J 2
(-2125 875);
DISPLAY 0.723404 (-2125 875);
PAINT GREEN (-2125 875);
FORCEPROP 2 LAST $SEC 1
J 2
(-2225 950);
DISPLAY 0.680851 (-2225 950);
PAINT MONO (-2225 950);
DISPLAY INVISIBLE (-2225 950);
FORCEPROP 2 LAST CDS_SEC 1
J 2
(-2225 950);
DISPLAY 0.680851 (-2225 950);
DISPLAY INVISIBLE (-2225 950);
FORCEPROP 2 LASTPIN (-2325 875) $PN 1
J 0
(-2315 885);
DISPLAY 0.808511 (-2315 885);
FORCEPROP 2 LASTPIN (-2475 875) $PN 2
J 2
(-2485 885);
DISPLAY 0.808511 (-2485 885);
FORCEPROP 2 LAST VALUE DIFF BUS_0.22UF
J 2
(-2550 875);
DISPLAY 0.553191 (-2550 875);
FORCEPROP 2 LAST TOLERANCE 20%
J 2
(-2475 925);
DISPLAY 0.553191 (-2475 925);
DISPLAY INVISIBLE (-2475 925);
FORCEPROP 2 LAST PACK_TYPE C0201
J 2
(-2575 925);
DISPLAY 0.553191 (-2575 925);
DISPLAY INVISIBLE (-2575 925);
FORCEPROP 1 LAST MATERIAL X6S
J 2
(-2391 954);
DISPLAY 0.574468 (-2391 954);
PAINT GREEN (-2391 954);
DISPLAY INVISIBLE (-2391 954);
FORCEPROP 2 LAST VOLTAGE 6.3V
J 2
(-2750 925);
DISPLAY 0.553191 (-2750 925);
DISPLAY INVISIBLE (-2750 925);
FORCEPROP 1 LAST PIN_NAMES_ROTATE TRUE
J 2
(-2400 875);
DISPLAY 0.489362 (-2400 875);
PAINT GREEN (-2400 875);
DISPLAY INVISIBLE (-2400 875);
FORCEPROP 2 LAST CDS_LIB pure_quanta
J 2
(-2400 875);
DISPLAY INVISIBLE (-2400 875);
FORCEPROP 1 LAST CDS_LMAN_SYM_OUTLINE -25,50,25,-50
J 2
(-2400 875);
DISPLAY 0.468085 (-2400 875);
PAINT GREEN (-2400 875);
DISPLAY INVISIBLE (-2400 875);
FORCEPROP 1 LAST PATH I62
J 2
(-2400 875);
DISPLAY 0.723404 (-2400 875);
DISPLAY INVISIBLE (-2400 875);
FORCEPROP 1 LAST PART_NUMBER SP_CH4221MEE01
J 2
(-2516 963);
DISPLAY 0.574468 (-2516 963);
PAINT GREEN (-2516 963);
DISPLAY INVISIBLE (-2516 963);
FORCEPROP 1 LAST LOCATION C6515
J 0
(-2150 950);
DISPLAY 1.021277 (-2150 950);
DISPLAY INVISIBLE (-2150 950);
FORCEADD Q_CAP_DIFFBUS..2
R 2
(-2400 1275);
FORCEPROP 1 LAST LOCATION C6511
J 2
(-2125 1275);
DISPLAY 0.723404 (-2125 1275);
PAINT GREEN (-2125 1275);
FORCEPROP 2 LAST $SEC 1
J 2
(-2225 1350);
DISPLAY 0.680851 (-2225 1350);
PAINT MONO (-2225 1350);
DISPLAY INVISIBLE (-2225 1350);
FORCEPROP 2 LAST CDS_SEC 1
J 2
(-2225 1350);
DISPLAY 0.680851 (-2225 1350);
DISPLAY INVISIBLE (-2225 1350);
FORCEPROP 2 LASTPIN (-2325 1275) $PN 1
J 0
(-2315 1285);
DISPLAY 0.808511 (-2315 1285);
FORCEPROP 2 LASTPIN (-2475 1275) $PN 2
J 2
(-2485 1285);
DISPLAY 0.808511 (-2485 1285);
FORCEPROP 2 LAST VALUE DIFF BUS_0.22UF
J 2
(-2550 1275);
DISPLAY 0.553191 (-2550 1275);
FORCEPROP 2 LAST TOLERANCE 20%
J 2
(-2475 1325);
DISPLAY 0.553191 (-2475 1325);
DISPLAY INVISIBLE (-2475 1325);
FORCEPROP 2 LAST PACK_TYPE C0201
J 2
(-2575 1325);
DISPLAY 0.553191 (-2575 1325);
DISPLAY INVISIBLE (-2575 1325);
FORCEPROP 1 LAST MATERIAL X6S
J 2
(-2391 1354);
DISPLAY 0.574468 (-2391 1354);
PAINT GREEN (-2391 1354);
DISPLAY INVISIBLE (-2391 1354);
FORCEPROP 2 LAST VOLTAGE 6.3V
J 2
(-2750 1325);
DISPLAY 0.553191 (-2750 1325);
DISPLAY INVISIBLE (-2750 1325);
FORCEPROP 1 LAST PIN_NAMES_ROTATE TRUE
J 2
(-2400 1275);
DISPLAY 0.489362 (-2400 1275);
PAINT GREEN (-2400 1275);
DISPLAY INVISIBLE (-2400 1275);
FORCEPROP 2 LAST CDS_LIB pure_quanta
J 2
(-2400 1275);
DISPLAY INVISIBLE (-2400 1275);
FORCEPROP 1 LAST CDS_LMAN_SYM_OUTLINE -25,50,25,-50
J 2
(-2400 1275);
DISPLAY 0.468085 (-2400 1275);
PAINT GREEN (-2400 1275);
DISPLAY INVISIBLE (-2400 1275);
FORCEPROP 1 LAST PATH I63
J 2
(-2400 1275);
DISPLAY 0.723404 (-2400 1275);
DISPLAY INVISIBLE (-2400 1275);
FORCEPROP 1 LAST PART_NUMBER SP_CH4221MEE01
J 2
(-2516 1363);
DISPLAY 0.574468 (-2516 1363);
PAINT GREEN (-2516 1363);
DISPLAY INVISIBLE (-2516 1363);
FORCEPROP 1 LAST LOCATION C6511
J 0
(-2150 1350);
DISPLAY 1.021277 (-2150 1350);
DISPLAY INVISIBLE (-2150 1350);
FORCEADD Q_CAP_DIFFBUS..2
R 2
(-2400 1225);
FORCEPROP 1 LAST LOCATION C6512
J 2
(-2125 1225);
DISPLAY 0.723404 (-2125 1225);
PAINT GREEN (-2125 1225);
FORCEPROP 2 LAST $SEC 1
J 2
(-2225 1300);
DISPLAY 0.680851 (-2225 1300);
PAINT MONO (-2225 1300);
DISPLAY INVISIBLE (-2225 1300);
FORCEPROP 2 LAST CDS_SEC 1
J 2
(-2225 1300);
DISPLAY 0.680851 (-2225 1300);
DISPLAY INVISIBLE (-2225 1300);
FORCEPROP 2 LASTPIN (-2325 1225) $PN 1
J 0
(-2315 1235);
DISPLAY 0.808511 (-2315 1235);
FORCEPROP 2 LASTPIN (-2475 1225) $PN 2
J 2
(-2485 1235);
DISPLAY 0.808511 (-2485 1235);
FORCEPROP 2 LAST VALUE DIFF BUS_0.22UF
J 2
(-2550 1225);
DISPLAY 0.553191 (-2550 1225);
FORCEPROP 2 LAST TOLERANCE 20%
J 2
(-2475 1275);
DISPLAY 0.553191 (-2475 1275);
DISPLAY INVISIBLE (-2475 1275);
FORCEPROP 2 LAST PACK_TYPE C0201
J 2
(-2575 1275);
DISPLAY 0.553191 (-2575 1275);
DISPLAY INVISIBLE (-2575 1275);
FORCEPROP 1 LAST MATERIAL X6S
J 2
(-2391 1304);
DISPLAY 0.574468 (-2391 1304);
PAINT GREEN (-2391 1304);
DISPLAY INVISIBLE (-2391 1304);
FORCEPROP 2 LAST VOLTAGE 6.3V
J 2
(-2750 1275);
DISPLAY 0.553191 (-2750 1275);
DISPLAY INVISIBLE (-2750 1275);
FORCEPROP 1 LAST PIN_NAMES_ROTATE TRUE
J 2
(-2400 1225);
DISPLAY 0.489362 (-2400 1225);
PAINT GREEN (-2400 1225);
DISPLAY INVISIBLE (-2400 1225);
FORCEPROP 2 LAST CDS_LIB pure_quanta
J 2
(-2400 1225);
DISPLAY INVISIBLE (-2400 1225);
FORCEPROP 1 LAST CDS_LMAN_SYM_OUTLINE -25,50,25,-50
J 2
(-2400 1225);
DISPLAY 0.468085 (-2400 1225);
PAINT GREEN (-2400 1225);
DISPLAY INVISIBLE (-2400 1225);
FORCEPROP 1 LAST PATH I64
J 2
(-2400 1225);
DISPLAY 0.723404 (-2400 1225);
DISPLAY INVISIBLE (-2400 1225);
FORCEPROP 1 LAST PART_NUMBER SP_CH4221MEE01
J 2
(-2516 1313);
DISPLAY 0.574468 (-2516 1313);
PAINT GREEN (-2516 1313);
DISPLAY INVISIBLE (-2516 1313);
FORCEPROP 1 LAST LOCATION C6512
J 0
(-2150 1300);
DISPLAY 1.021277 (-2150 1300);
DISPLAY INVISIBLE (-2150 1300);
FORCEADD Q_CAP_DIFFBUS..2
R 2
(-2400 1475);
FORCEPROP 1 LAST LOCATION C6509
J 2
(-2125 1475);
DISPLAY 0.723404 (-2125 1475);
PAINT GREEN (-2125 1475);
FORCEPROP 2 LAST $SEC 1
J 2
(-2225 1550);
DISPLAY 0.680851 (-2225 1550);
PAINT MONO (-2225 1550);
DISPLAY INVISIBLE (-2225 1550);
FORCEPROP 2 LAST CDS_SEC 1
J 2
(-2225 1550);
DISPLAY 0.680851 (-2225 1550);
DISPLAY INVISIBLE (-2225 1550);
FORCEPROP 2 LASTPIN (-2325 1475) $PN 1
J 0
(-2315 1485);
DISPLAY 0.808511 (-2315 1485);
FORCEPROP 2 LASTPIN (-2475 1475) $PN 2
J 2
(-2485 1485);
DISPLAY 0.808511 (-2485 1485);
FORCEPROP 2 LAST VALUE DIFF BUS_0.22UF
J 2
(-2550 1475);
DISPLAY 0.553191 (-2550 1475);
FORCEPROP 2 LAST TOLERANCE 20%
J 2
(-2475 1525);
DISPLAY 0.553191 (-2475 1525);
DISPLAY INVISIBLE (-2475 1525);
FORCEPROP 2 LAST PACK_TYPE C0201
J 2
(-2575 1525);
DISPLAY 0.553191 (-2575 1525);
DISPLAY INVISIBLE (-2575 1525);
FORCEPROP 1 LAST MATERIAL X6S
J 2
(-2391 1554);
DISPLAY 0.574468 (-2391 1554);
PAINT GREEN (-2391 1554);
DISPLAY INVISIBLE (-2391 1554);
FORCEPROP 2 LAST VOLTAGE 6.3V
J 2
(-2750 1525);
DISPLAY 0.553191 (-2750 1525);
DISPLAY INVISIBLE (-2750 1525);
FORCEPROP 1 LAST PIN_NAMES_ROTATE TRUE
J 2
(-2400 1475);
DISPLAY 0.489362 (-2400 1475);
PAINT GREEN (-2400 1475);
DISPLAY INVISIBLE (-2400 1475);
FORCEPROP 1 LAST CDS_LMAN_SYM_OUTLINE -25,50,25,-50
J 2
(-2400 1475);
DISPLAY 0.468085 (-2400 1475);
PAINT GREEN (-2400 1475);
DISPLAY INVISIBLE (-2400 1475);
FORCEPROP 2 LAST CDS_LIB pure_quanta
J 2
(-2400 1475);
DISPLAY INVISIBLE (-2400 1475);
FORCEPROP 1 LAST PATH I65
J 2
(-2400 1475);
DISPLAY 0.723404 (-2400 1475);
DISPLAY INVISIBLE (-2400 1475);
FORCEPROP 1 LAST PART_NUMBER SP_CH4221MEE01
J 2
(-2516 1563);
DISPLAY 0.574468 (-2516 1563);
PAINT GREEN (-2516 1563);
DISPLAY INVISIBLE (-2516 1563);
FORCEPROP 1 LAST LOCATION C6509
J 0
(-2150 1550);
DISPLAY 1.021277 (-2150 1550);
DISPLAY INVISIBLE (-2150 1550);
FORCEADD Q_CAP_DIFFBUS..2
R 2
(-2400 1425);
FORCEPROP 1 LAST LOCATION C6510
J 2
(-2125 1425);
DISPLAY 0.723404 (-2125 1425);
PAINT GREEN (-2125 1425);
FORCEPROP 2 LAST $SEC 1
J 2
(-2225 1500);
DISPLAY 0.680851 (-2225 1500);
PAINT MONO (-2225 1500);
DISPLAY INVISIBLE (-2225 1500);
FORCEPROP 2 LAST CDS_SEC 1
J 2
(-2225 1500);
DISPLAY 0.680851 (-2225 1500);
DISPLAY INVISIBLE (-2225 1500);
FORCEPROP 2 LASTPIN (-2325 1425) $PN 1
J 0
(-2315 1435);
DISPLAY 0.808511 (-2315 1435);
FORCEPROP 2 LASTPIN (-2475 1425) $PN 2
J 2
(-2485 1435);
DISPLAY 0.808511 (-2485 1435);
FORCEPROP 2 LAST VALUE DIFF BUS_0.22UF
J 2
(-2550 1425);
DISPLAY 0.553191 (-2550 1425);
FORCEPROP 2 LAST TOLERANCE 20%
J 2
(-2475 1475);
DISPLAY 0.553191 (-2475 1475);
DISPLAY INVISIBLE (-2475 1475);
FORCEPROP 2 LAST PACK_TYPE C0201
J 2
(-2575 1475);
DISPLAY 0.553191 (-2575 1475);
DISPLAY INVISIBLE (-2575 1475);
FORCEPROP 1 LAST MATERIAL X6S
J 2
(-2391 1504);
DISPLAY 0.574468 (-2391 1504);
PAINT GREEN (-2391 1504);
DISPLAY INVISIBLE (-2391 1504);
FORCEPROP 2 LAST VOLTAGE 6.3V
J 2
(-2750 1475);
DISPLAY 0.553191 (-2750 1475);
DISPLAY INVISIBLE (-2750 1475);
FORCEPROP 1 LAST PIN_NAMES_ROTATE TRUE
J 2
(-2400 1425);
DISPLAY 0.489362 (-2400 1425);
PAINT GREEN (-2400 1425);
DISPLAY INVISIBLE (-2400 1425);
FORCEPROP 1 LAST CDS_LMAN_SYM_OUTLINE -25,50,25,-50
J 2
(-2400 1425);
DISPLAY 0.468085 (-2400 1425);
PAINT GREEN (-2400 1425);
DISPLAY INVISIBLE (-2400 1425);
FORCEPROP 2 LAST CDS_LIB pure_quanta
J 2
(-2400 1425);
DISPLAY INVISIBLE (-2400 1425);
FORCEPROP 1 LAST PATH I66
J 2
(-2400 1425);
DISPLAY 0.723404 (-2400 1425);
DISPLAY INVISIBLE (-2400 1425);
FORCEPROP 1 LAST PART_NUMBER SP_CH4221MEE01
J 2
(-2516 1513);
DISPLAY 0.574468 (-2516 1513);
PAINT GREEN (-2516 1513);
DISPLAY INVISIBLE (-2516 1513);
FORCEPROP 1 LAST LOCATION C6510
J 0
(-2150 1500);
DISPLAY 1.021277 (-2150 1500);
DISPLAY INVISIBLE (-2150 1500);
FORCEADD TAP..1
(-1850 1075);
FORCEPROP 3 LASTPIN (-1900 1075) SIG_NAME P5E_CPU0_P0_TX_BUF_C_DP<6>
J 0
(-1890 1085);
DISPLAY 0.659574 (-1890 1085);
PAINT MONO (-1890 1085);
DISPLAY INVISIBLE (-1890 1085);
FORCEPROP 1 LASTPIN (-1900 1075) BN 6
J 0
(-1912 1083);
DISPLAY 0.680851 (-1912 1083);
PAINT GREEN (-1912 1083);
FORCEPROP 2 LAST CDS_LIB standard
J 0
(-1850 1075);
DISPLAY INVISIBLE (-1850 1075);
FORCEPROP 1 LAST BODY_TYPE PLUMBING
J 0
(-1850 1125);
DISPLAY 0.872340 (-1850 1125);
PAINT GREEN (-1850 1125);
DISPLAY INVISIBLE (-1850 1125);
FORCEPROP 1 LAST HDL_TAP TRUE
J 0
(-1525 950);
DISPLAY 0.872340 (-1525 950);
DISPLAY INVISIBLE (-1525 950);
FORCEPROP 1 LAST PATH I67
J 0
(-1852 1075);
DISPLAY 0.872340 (-1852 1075);
PAINT GREEN (-1852 1075);
DISPLAY INVISIBLE (-1852 1075);
FORCEADD TAP..1
(-1850 875);
FORCEPROP 3 LASTPIN (-1900 875) SIG_NAME P5E_CPU0_P0_TX_BUF_C_DP<7>
J 0
(-1890 885);
DISPLAY 0.659574 (-1890 885);
PAINT MONO (-1890 885);
DISPLAY INVISIBLE (-1890 885);
FORCEPROP 1 LASTPIN (-1900 875) BN 7
J 0
(-1912 883);
DISPLAY 0.680851 (-1912 883);
PAINT GREEN (-1912 883);
FORCEPROP 2 LAST CDS_LIB standard
J 0
(-1850 875);
DISPLAY INVISIBLE (-1850 875);
FORCEPROP 1 LAST BODY_TYPE PLUMBING
J 0
(-1850 925);
DISPLAY 0.872340 (-1850 925);
PAINT GREEN (-1850 925);
DISPLAY INVISIBLE (-1850 925);
FORCEPROP 1 LAST HDL_TAP TRUE
J 0
(-1525 750);
DISPLAY 0.872340 (-1525 750);
DISPLAY INVISIBLE (-1525 750);
FORCEPROP 1 LAST PATH I68
J 0
(-1852 875);
DISPLAY 0.872340 (-1852 875);
PAINT GREEN (-1852 875);
DISPLAY INVISIBLE (-1852 875);
FORCEADD TAP..1
(-1850 1275);
FORCEPROP 3 LASTPIN (-1900 1275) SIG_NAME P5E_CPU0_P0_TX_BUF_C_DP<5>
J 0
(-1890 1285);
DISPLAY 0.659574 (-1890 1285);
PAINT MONO (-1890 1285);
DISPLAY INVISIBLE (-1890 1285);
FORCEPROP 1 LASTPIN (-1900 1275) BN 5
J 0
(-1912 1283);
DISPLAY 0.680851 (-1912 1283);
PAINT GREEN (-1912 1283);
FORCEPROP 2 LAST CDS_LIB standard
J 0
(-1850 1275);
DISPLAY INVISIBLE (-1850 1275);
FORCEPROP 1 LAST BODY_TYPE PLUMBING
J 0
(-1850 1325);
DISPLAY 0.872340 (-1850 1325);
PAINT GREEN (-1850 1325);
DISPLAY INVISIBLE (-1850 1325);
FORCEPROP 1 LAST HDL_TAP TRUE
J 0
(-1525 1150);
DISPLAY 0.872340 (-1525 1150);
DISPLAY INVISIBLE (-1525 1150);
FORCEPROP 1 LAST PATH I69
J 0
(-1852 1275);
DISPLAY 0.872340 (-1852 1275);
PAINT GREEN (-1852 1275);
DISPLAY INVISIBLE (-1852 1275);
FORCEADD TAP..1
(-7075 4300);
FORCEPROP 3 LASTPIN (-7125 4300) SIG_NAME P5E_CPU0_P0_TX_BUF_DP<10>
J 0
(-7115 4310);
DISPLAY 0.659574 (-7115 4310);
PAINT MONO (-7115 4310);
DISPLAY INVISIBLE (-7115 4310);
FORCEPROP 1 LASTPIN (-7125 4300) BN 10
J 0
(-7137 4308);
DISPLAY 0.680851 (-7137 4308);
PAINT GREEN (-7137 4308);
FORCEPROP 2 LAST CDS_LIB standard
J 0
(-7075 4300);
DISPLAY INVISIBLE (-7075 4300);
FORCEPROP 1 LAST BODY_TYPE PLUMBING
J 0
(-7075 4350);
DISPLAY 0.872340 (-7075 4350);
PAINT GREEN (-7075 4350);
DISPLAY INVISIBLE (-7075 4350);
FORCEPROP 1 LAST HDL_TAP TRUE
J 0
(-6750 4175);
DISPLAY 0.872340 (-6750 4175);
DISPLAY INVISIBLE (-6750 4175);
FORCEPROP 1 LAST PATH I7
J 0
(-7077 4300);
DISPLAY 0.872340 (-7077 4300);
PAINT GREEN (-7077 4300);
DISPLAY INVISIBLE (-7077 4300);
FORCEADD TAP..1
(-1850 1475);
FORCEPROP 3 LASTPIN (-1900 1475) SIG_NAME P5E_CPU0_P0_TX_BUF_C_DP<4>
J 0
(-1890 1485);
DISPLAY 0.659574 (-1890 1485);
PAINT MONO (-1890 1485);
DISPLAY INVISIBLE (-1890 1485);
FORCEPROP 1 LASTPIN (-1900 1475) BN 4
J 0
(-1912 1483);
DISPLAY 0.680851 (-1912 1483);
PAINT GREEN (-1912 1483);
FORCEPROP 2 LAST CDS_LIB standard
J 0
(-1850 1475);
DISPLAY INVISIBLE (-1850 1475);
FORCEPROP 1 LAST BODY_TYPE PLUMBING
J 0
(-1850 1525);
DISPLAY 0.872340 (-1850 1525);
PAINT GREEN (-1850 1525);
DISPLAY INVISIBLE (-1850 1525);
FORCEPROP 1 LAST HDL_TAP TRUE
J 0
(-1525 1350);
DISPLAY 0.872340 (-1525 1350);
DISPLAY INVISIBLE (-1525 1350);
FORCEPROP 1 LAST PATH I70
J 0
(-1852 1475);
DISPLAY 0.872340 (-1852 1475);
PAINT GREEN (-1852 1475);
DISPLAY INVISIBLE (-1852 1475);
FORCEADD Q_CAP_DIFFBUS..2
R 2
(-2400 1625);
FORCEPROP 1 LAST LOCATION C6508
J 2
(-2125 1625);
DISPLAY 0.723404 (-2125 1625);
PAINT GREEN (-2125 1625);
FORCEPROP 2 LAST $SEC 1
J 2
(-2225 1700);
DISPLAY 0.680851 (-2225 1700);
PAINT MONO (-2225 1700);
DISPLAY INVISIBLE (-2225 1700);
FORCEPROP 2 LAST CDS_SEC 1
J 2
(-2225 1700);
DISPLAY 0.680851 (-2225 1700);
DISPLAY INVISIBLE (-2225 1700);
FORCEPROP 2 LASTPIN (-2325 1625) $PN 1
J 0
(-2315 1635);
DISPLAY 0.808511 (-2315 1635);
FORCEPROP 2 LASTPIN (-2475 1625) $PN 2
J 2
(-2485 1635);
DISPLAY 0.808511 (-2485 1635);
FORCEPROP 2 LAST VALUE DIFF BUS_0.22UF
J 2
(-2550 1625);
DISPLAY 0.553191 (-2550 1625);
FORCEPROP 2 LAST TOLERANCE 20%
J 2
(-2475 1675);
DISPLAY 0.553191 (-2475 1675);
DISPLAY INVISIBLE (-2475 1675);
FORCEPROP 2 LAST PACK_TYPE C0201
J 2
(-2575 1675);
DISPLAY 0.553191 (-2575 1675);
DISPLAY INVISIBLE (-2575 1675);
FORCEPROP 1 LAST MATERIAL X6S
J 2
(-2391 1704);
DISPLAY 0.574468 (-2391 1704);
PAINT GREEN (-2391 1704);
DISPLAY INVISIBLE (-2391 1704);
FORCEPROP 2 LAST VOLTAGE 6.3V
J 2
(-2750 1675);
DISPLAY 0.553191 (-2750 1675);
DISPLAY INVISIBLE (-2750 1675);
FORCEPROP 1 LAST PIN_NAMES_ROTATE TRUE
J 2
(-2400 1625);
DISPLAY 0.489362 (-2400 1625);
PAINT GREEN (-2400 1625);
DISPLAY INVISIBLE (-2400 1625);
FORCEPROP 2 LAST CDS_LIB pure_quanta
J 2
(-2400 1625);
DISPLAY INVISIBLE (-2400 1625);
FORCEPROP 1 LAST CDS_LMAN_SYM_OUTLINE -25,50,25,-50
J 2
(-2400 1625);
DISPLAY 0.468085 (-2400 1625);
PAINT GREEN (-2400 1625);
DISPLAY INVISIBLE (-2400 1625);
FORCEPROP 1 LAST PATH I71
J 2
(-2400 1625);
DISPLAY 0.723404 (-2400 1625);
DISPLAY INVISIBLE (-2400 1625);
FORCEPROP 1 LAST PART_NUMBER SP_CH4221MEE01
J 2
(-2516 1713);
DISPLAY 0.574468 (-2516 1713);
PAINT GREEN (-2516 1713);
DISPLAY INVISIBLE (-2516 1713);
FORCEPROP 1 LAST LOCATION C6508
J 0
(-2150 1700);
DISPLAY 1.021277 (-2150 1700);
DISPLAY INVISIBLE (-2150 1700);
FORCEADD Q_CAP_DIFFBUS..2
R 2
(-2400 1825);
FORCEPROP 1 LAST LOCATION C6506
J 2
(-2125 1825);
DISPLAY 0.723404 (-2125 1825);
PAINT GREEN (-2125 1825);
FORCEPROP 2 LAST $SEC 1
J 2
(-2225 1900);
DISPLAY 0.680851 (-2225 1900);
PAINT MONO (-2225 1900);
DISPLAY INVISIBLE (-2225 1900);
FORCEPROP 2 LAST CDS_SEC 1
J 2
(-2225 1900);
DISPLAY 0.680851 (-2225 1900);
DISPLAY INVISIBLE (-2225 1900);
FORCEPROP 2 LASTPIN (-2325 1825) $PN 1
J 0
(-2315 1835);
DISPLAY 0.808511 (-2315 1835);
FORCEPROP 2 LASTPIN (-2475 1825) $PN 2
J 2
(-2485 1835);
DISPLAY 0.808511 (-2485 1835);
FORCEPROP 2 LAST VALUE DIFF BUS_0.22UF
J 2
(-2550 1825);
DISPLAY 0.553191 (-2550 1825);
FORCEPROP 2 LAST TOLERANCE 20%
J 2
(-2475 1875);
DISPLAY 0.553191 (-2475 1875);
DISPLAY INVISIBLE (-2475 1875);
FORCEPROP 2 LAST PACK_TYPE C0201
J 2
(-2575 1875);
DISPLAY 0.553191 (-2575 1875);
DISPLAY INVISIBLE (-2575 1875);
FORCEPROP 1 LAST MATERIAL X6S
J 2
(-2391 1904);
DISPLAY 0.574468 (-2391 1904);
PAINT GREEN (-2391 1904);
DISPLAY INVISIBLE (-2391 1904);
FORCEPROP 2 LAST VOLTAGE 6.3V
J 2
(-2750 1875);
DISPLAY 0.553191 (-2750 1875);
DISPLAY INVISIBLE (-2750 1875);
FORCEPROP 1 LAST PIN_NAMES_ROTATE TRUE
J 2
(-2400 1825);
DISPLAY 0.489362 (-2400 1825);
PAINT GREEN (-2400 1825);
DISPLAY INVISIBLE (-2400 1825);
FORCEPROP 2 LAST CDS_LIB pure_quanta
J 2
(-2400 1825);
DISPLAY INVISIBLE (-2400 1825);
FORCEPROP 1 LAST CDS_LMAN_SYM_OUTLINE -25,50,25,-50
J 2
(-2400 1825);
DISPLAY 0.468085 (-2400 1825);
PAINT GREEN (-2400 1825);
DISPLAY INVISIBLE (-2400 1825);
FORCEPROP 1 LAST PATH I72
J 2
(-2400 1825);
DISPLAY 0.723404 (-2400 1825);
DISPLAY INVISIBLE (-2400 1825);
FORCEPROP 1 LAST PART_NUMBER SP_CH4221MEE01
J 2
(-2516 1913);
DISPLAY 0.574468 (-2516 1913);
PAINT GREEN (-2516 1913);
DISPLAY INVISIBLE (-2516 1913);
FORCEPROP 1 LAST LOCATION C6506
J 0
(-2150 1900);
DISPLAY 1.021277 (-2150 1900);
DISPLAY INVISIBLE (-2150 1900);
FORCEADD Q_CAP_DIFFBUS..2
R 2
(-2400 1675);
FORCEPROP 1 LAST LOCATION C6507
J 2
(-2125 1675);
DISPLAY 0.723404 (-2125 1675);
PAINT GREEN (-2125 1675);
FORCEPROP 2 LAST $SEC 1
J 2
(-2225 1750);
DISPLAY 0.680851 (-2225 1750);
PAINT MONO (-2225 1750);
DISPLAY INVISIBLE (-2225 1750);
FORCEPROP 2 LAST CDS_SEC 1
J 2
(-2225 1750);
DISPLAY 0.680851 (-2225 1750);
DISPLAY INVISIBLE (-2225 1750);
FORCEPROP 2 LASTPIN (-2325 1675) $PN 1
J 0
(-2315 1685);
DISPLAY 0.808511 (-2315 1685);
FORCEPROP 2 LASTPIN (-2475 1675) $PN 2
J 2
(-2485 1685);
DISPLAY 0.808511 (-2485 1685);
FORCEPROP 2 LAST VALUE DIFF BUS_0.22UF
J 2
(-2550 1675);
DISPLAY 0.553191 (-2550 1675);
FORCEPROP 2 LAST TOLERANCE 20%
J 2
(-2475 1725);
DISPLAY 0.553191 (-2475 1725);
DISPLAY INVISIBLE (-2475 1725);
FORCEPROP 2 LAST PACK_TYPE C0201
J 2
(-2575 1725);
DISPLAY 0.553191 (-2575 1725);
DISPLAY INVISIBLE (-2575 1725);
FORCEPROP 1 LAST MATERIAL X6S
J 2
(-2391 1754);
DISPLAY 0.574468 (-2391 1754);
PAINT GREEN (-2391 1754);
DISPLAY INVISIBLE (-2391 1754);
FORCEPROP 2 LAST VOLTAGE 6.3V
J 2
(-2750 1725);
DISPLAY 0.553191 (-2750 1725);
DISPLAY INVISIBLE (-2750 1725);
FORCEPROP 1 LAST PIN_NAMES_ROTATE TRUE
J 2
(-2400 1675);
DISPLAY 0.489362 (-2400 1675);
PAINT GREEN (-2400 1675);
DISPLAY INVISIBLE (-2400 1675);
FORCEPROP 2 LAST CDS_LIB pure_quanta
J 2
(-2400 1675);
DISPLAY INVISIBLE (-2400 1675);
FORCEPROP 1 LAST CDS_LMAN_SYM_OUTLINE -25,50,25,-50
J 2
(-2400 1675);
DISPLAY 0.468085 (-2400 1675);
PAINT GREEN (-2400 1675);
DISPLAY INVISIBLE (-2400 1675);
FORCEPROP 1 LAST PATH I73
J 2
(-2400 1675);
DISPLAY 0.723404 (-2400 1675);
DISPLAY INVISIBLE (-2400 1675);
FORCEPROP 1 LAST PART_NUMBER SP_CH4221MEE01
J 2
(-2516 1763);
DISPLAY 0.574468 (-2516 1763);
PAINT GREEN (-2516 1763);
DISPLAY INVISIBLE (-2516 1763);
FORCEPROP 1 LAST LOCATION C6507
J 0
(-2150 1750);
DISPLAY 1.021277 (-2150 1750);
DISPLAY INVISIBLE (-2150 1750);
FORCEADD Q_CAP_DIFFBUS..2
R 2
(-2400 1875);
FORCEPROP 1 LAST LOCATION C6505
J 2
(-2125 1875);
DISPLAY 0.723404 (-2125 1875);
PAINT GREEN (-2125 1875);
FORCEPROP 2 LAST $SEC 1
J 2
(-2225 1950);
DISPLAY 0.680851 (-2225 1950);
PAINT MONO (-2225 1950);
DISPLAY INVISIBLE (-2225 1950);
FORCEPROP 2 LAST CDS_SEC 1
J 2
(-2225 1950);
DISPLAY 0.680851 (-2225 1950);
DISPLAY INVISIBLE (-2225 1950);
FORCEPROP 2 LASTPIN (-2325 1875) $PN 1
J 0
(-2315 1885);
DISPLAY 0.808511 (-2315 1885);
FORCEPROP 2 LASTPIN (-2475 1875) $PN 2
J 2
(-2485 1885);
DISPLAY 0.808511 (-2485 1885);
FORCEPROP 2 LAST VALUE DIFF BUS_0.22UF
J 2
(-2550 1875);
DISPLAY 0.553191 (-2550 1875);
FORCEPROP 2 LAST TOLERANCE 20%
J 2
(-2475 1925);
DISPLAY 0.553191 (-2475 1925);
DISPLAY INVISIBLE (-2475 1925);
FORCEPROP 2 LAST PACK_TYPE C0201
J 2
(-2575 1925);
DISPLAY 0.553191 (-2575 1925);
DISPLAY INVISIBLE (-2575 1925);
FORCEPROP 1 LAST MATERIAL X6S
J 2
(-2391 1954);
DISPLAY 0.574468 (-2391 1954);
PAINT GREEN (-2391 1954);
DISPLAY INVISIBLE (-2391 1954);
FORCEPROP 2 LAST VOLTAGE 6.3V
J 2
(-2750 1925);
DISPLAY 0.553191 (-2750 1925);
DISPLAY INVISIBLE (-2750 1925);
FORCEPROP 1 LAST PIN_NAMES_ROTATE TRUE
J 2
(-2400 1875);
DISPLAY 0.489362 (-2400 1875);
PAINT GREEN (-2400 1875);
DISPLAY INVISIBLE (-2400 1875);
FORCEPROP 2 LAST CDS_LIB pure_quanta
J 2
(-2400 1875);
DISPLAY INVISIBLE (-2400 1875);
FORCEPROP 1 LAST CDS_LMAN_SYM_OUTLINE -25,50,25,-50
J 2
(-2400 1875);
DISPLAY 0.468085 (-2400 1875);
PAINT GREEN (-2400 1875);
DISPLAY INVISIBLE (-2400 1875);
FORCEPROP 1 LAST PATH I74
J 2
(-2400 1875);
DISPLAY 0.723404 (-2400 1875);
DISPLAY INVISIBLE (-2400 1875);
FORCEPROP 1 LAST PART_NUMBER SP_CH4221MEE01
J 2
(-2516 1963);
DISPLAY 0.574468 (-2516 1963);
PAINT GREEN (-2516 1963);
DISPLAY INVISIBLE (-2516 1963);
FORCEPROP 1 LAST LOCATION C6505
J 0
(-2150 1950);
DISPLAY 1.021277 (-2150 1950);
DISPLAY INVISIBLE (-2150 1950);
FORCEADD Q_CAP_DIFFBUS..2
R 2
(-2400 2075);
FORCEPROP 1 LAST LOCATION C6503
J 2
(-2100 2075);
DISPLAY 0.723404 (-2100 2075);
PAINT GREEN (-2100 2075);
FORCEPROP 2 LAST $SEC 1
J 2
(-2225 2150);
DISPLAY 0.680851 (-2225 2150);
PAINT MONO (-2225 2150);
DISPLAY INVISIBLE (-2225 2150);
FORCEPROP 2 LAST CDS_SEC 1
J 2
(-2225 2150);
DISPLAY 0.680851 (-2225 2150);
DISPLAY INVISIBLE (-2225 2150);
FORCEPROP 2 LASTPIN (-2325 2075) $PN 1
J 0
(-2315 2085);
DISPLAY 0.808511 (-2315 2085);
FORCEPROP 2 LASTPIN (-2475 2075) $PN 2
J 2
(-2485 2085);
DISPLAY 0.808511 (-2485 2085);
FORCEPROP 2 LAST VALUE DIFF BUS_0.22UF
J 2
(-2550 2075);
DISPLAY 0.553191 (-2550 2075);
FORCEPROP 2 LAST TOLERANCE 20%
J 2
(-2475 2125);
DISPLAY 0.553191 (-2475 2125);
DISPLAY INVISIBLE (-2475 2125);
FORCEPROP 2 LAST PACK_TYPE C0201
J 2
(-2575 2125);
DISPLAY 0.553191 (-2575 2125);
DISPLAY INVISIBLE (-2575 2125);
FORCEPROP 1 LAST MATERIAL X6S
J 2
(-2391 2154);
DISPLAY 0.574468 (-2391 2154);
PAINT GREEN (-2391 2154);
DISPLAY INVISIBLE (-2391 2154);
FORCEPROP 2 LAST VOLTAGE 6.3V
J 2
(-2750 2125);
DISPLAY 0.553191 (-2750 2125);
DISPLAY INVISIBLE (-2750 2125);
FORCEPROP 1 LAST PIN_NAMES_ROTATE TRUE
J 2
(-2400 2075);
DISPLAY 0.489362 (-2400 2075);
PAINT GREEN (-2400 2075);
DISPLAY INVISIBLE (-2400 2075);
FORCEPROP 2 LAST CDS_LIB pure_quanta
J 2
(-2400 2075);
DISPLAY INVISIBLE (-2400 2075);
FORCEPROP 1 LAST CDS_LMAN_SYM_OUTLINE -25,50,25,-50
J 2
(-2400 2075);
DISPLAY 0.468085 (-2400 2075);
PAINT GREEN (-2400 2075);
DISPLAY INVISIBLE (-2400 2075);
FORCEPROP 1 LAST PATH I75
J 2
(-2400 2075);
DISPLAY 0.723404 (-2400 2075);
DISPLAY INVISIBLE (-2400 2075);
FORCEPROP 1 LAST PART_NUMBER SP_CH4221MEE01
J 2
(-2516 2163);
DISPLAY 0.574468 (-2516 2163);
PAINT GREEN (-2516 2163);
DISPLAY INVISIBLE (-2516 2163);
FORCEPROP 1 LAST LOCATION C6503
J 0
(-2150 2150);
DISPLAY 1.021277 (-2150 2150);
DISPLAY INVISIBLE (-2150 2150);
FORCEADD Q_CAP_DIFFBUS..2
R 2
(-2400 2025);
FORCEPROP 1 LAST LOCATION C6504
J 2
(-2100 2025);
DISPLAY 0.723404 (-2100 2025);
PAINT GREEN (-2100 2025);
FORCEPROP 2 LAST $SEC 1
J 2
(-2225 2100);
DISPLAY 0.680851 (-2225 2100);
PAINT MONO (-2225 2100);
DISPLAY INVISIBLE (-2225 2100);
FORCEPROP 2 LAST CDS_SEC 1
J 2
(-2225 2100);
DISPLAY 0.680851 (-2225 2100);
DISPLAY INVISIBLE (-2225 2100);
FORCEPROP 2 LASTPIN (-2325 2025) $PN 1
J 0
(-2315 2035);
DISPLAY 0.808511 (-2315 2035);
FORCEPROP 2 LASTPIN (-2475 2025) $PN 2
J 2
(-2485 2035);
DISPLAY 0.808511 (-2485 2035);
FORCEPROP 2 LAST VALUE DIFF BUS_0.22UF
J 2
(-2550 2025);
DISPLAY 0.553191 (-2550 2025);
FORCEPROP 2 LAST TOLERANCE 20%
J 2
(-2475 2075);
DISPLAY 0.553191 (-2475 2075);
DISPLAY INVISIBLE (-2475 2075);
FORCEPROP 2 LAST PACK_TYPE C0201
J 2
(-2575 2075);
DISPLAY 0.553191 (-2575 2075);
DISPLAY INVISIBLE (-2575 2075);
FORCEPROP 1 LAST MATERIAL X6S
J 2
(-2391 2104);
DISPLAY 0.574468 (-2391 2104);
PAINT GREEN (-2391 2104);
DISPLAY INVISIBLE (-2391 2104);
FORCEPROP 2 LAST VOLTAGE 6.3V
J 2
(-2750 2075);
DISPLAY 0.553191 (-2750 2075);
DISPLAY INVISIBLE (-2750 2075);
FORCEPROP 1 LAST PIN_NAMES_ROTATE TRUE
J 2
(-2400 2025);
DISPLAY 0.489362 (-2400 2025);
PAINT GREEN (-2400 2025);
DISPLAY INVISIBLE (-2400 2025);
FORCEPROP 2 LAST CDS_LIB pure_quanta
J 2
(-2400 2025);
DISPLAY INVISIBLE (-2400 2025);
FORCEPROP 1 LAST CDS_LMAN_SYM_OUTLINE -25,50,25,-50
J 2
(-2400 2025);
DISPLAY 0.468085 (-2400 2025);
PAINT GREEN (-2400 2025);
DISPLAY INVISIBLE (-2400 2025);
FORCEPROP 1 LAST PATH I76
J 2
(-2400 2025);
DISPLAY 0.723404 (-2400 2025);
DISPLAY INVISIBLE (-2400 2025);
FORCEPROP 1 LAST PART_NUMBER SP_CH4221MEE01
J 2
(-2516 2113);
DISPLAY 0.574468 (-2516 2113);
PAINT GREEN (-2516 2113);
DISPLAY INVISIBLE (-2516 2113);
FORCEPROP 1 LAST LOCATION C6504
J 0
(-2150 2100);
DISPLAY 1.021277 (-2150 2100);
DISPLAY INVISIBLE (-2150 2100);
FORCEADD Q_CAP_DIFFBUS..2
R 2
(-2400 2275);
FORCEPROP 1 LAST LOCATION C6501
J 2
(-2100 2275);
DISPLAY 0.723404 (-2100 2275);
PAINT GREEN (-2100 2275);
FORCEPROP 2 LAST $SEC 1
J 2
(-2225 2350);
DISPLAY 0.680851 (-2225 2350);
PAINT MONO (-2225 2350);
DISPLAY INVISIBLE (-2225 2350);
FORCEPROP 2 LAST CDS_SEC 1
J 2
(-2225 2350);
DISPLAY 0.680851 (-2225 2350);
DISPLAY INVISIBLE (-2225 2350);
FORCEPROP 2 LASTPIN (-2325 2275) $PN 1
J 0
(-2315 2285);
DISPLAY 0.808511 (-2315 2285);
FORCEPROP 2 LASTPIN (-2475 2275) $PN 2
J 2
(-2485 2285);
DISPLAY 0.808511 (-2485 2285);
FORCEPROP 1 LAST MATERIAL X6S
J 2
(-2491 2479);
DISPLAY 0.574468 (-2491 2479);
PAINT GREEN (-2491 2479);
FORCEPROP 2 LAST PACK_TYPE C0201
J 2
(-2450 2425);
DISPLAY 0.553191 (-2450 2425);
PAINT GREEN (-2450 2425);
FORCEPROP 2 LAST VALUE DIFF BUS_0.22UF
J 2
(-2550 2275);
DISPLAY 0.553191 (-2550 2275);
FORCEPROP 2 LAST TOLERANCE 20%
J 2
(-2350 2425);
DISPLAY 0.553191 (-2350 2425);
PAINT GREEN (-2350 2425);
FORCEPROP 2 LAST VOLTAGE 6.3V
J 2
(-2225 2425);
DISPLAY 0.553191 (-2225 2425);
PAINT GREEN (-2225 2425);
FORCEPROP 1 LAST PIN_NAMES_ROTATE TRUE
J 2
(-2400 2275);
DISPLAY 0.489362 (-2400 2275);
PAINT GREEN (-2400 2275);
DISPLAY INVISIBLE (-2400 2275);
FORCEPROP 1 LAST CDS_LMAN_SYM_OUTLINE -25,50,25,-50
J 2
(-2400 2275);
DISPLAY 0.468085 (-2400 2275);
PAINT GREEN (-2400 2275);
DISPLAY INVISIBLE (-2400 2275);
FORCEPROP 2 LAST CDS_LIB pure_quanta
J 2
(-2400 2275);
DISPLAY INVISIBLE (-2400 2275);
FORCEPROP 1 LAST PATH I77
J 2
(-2400 2275);
DISPLAY 0.723404 (-2400 2275);
DISPLAY INVISIBLE (-2400 2275);
FORCEPROP 1 LAST PART_NUMBER SP_CH4221MEE01
J 2
(-2216 2363);
DISPLAY 0.574468 (-2216 2363);
PAINT GREEN (-2216 2363);
DISPLAY INVISIBLE (-2216 2363);
FORCEPROP 1 LAST LOCATION C6501
J 0
(-2150 2350);
DISPLAY 1.021277 (-2150 2350);
DISPLAY INVISIBLE (-2150 2350);
FORCEADD Q_CAP_DIFFBUS..2
R 2
(-2400 2225);
FORCEPROP 1 LAST LOCATION C6502
J 2
(-2100 2225);
DISPLAY 0.723404 (-2100 2225);
PAINT GREEN (-2100 2225);
FORCEPROP 2 LAST $SEC 1
J 2
(-2225 2300);
DISPLAY 0.680851 (-2225 2300);
PAINT MONO (-2225 2300);
DISPLAY INVISIBLE (-2225 2300);
FORCEPROP 2 LAST CDS_SEC 1
J 2
(-2225 2300);
DISPLAY 0.680851 (-2225 2300);
DISPLAY INVISIBLE (-2225 2300);
FORCEPROP 2 LASTPIN (-2325 2225) $PN 1
J 0
(-2315 2235);
DISPLAY 0.808511 (-2315 2235);
FORCEPROP 2 LASTPIN (-2475 2225) $PN 2
J 2
(-2485 2235);
DISPLAY 0.808511 (-2485 2235);
FORCEPROP 2 LAST VALUE DIFF BUS_0.22UF
J 2
(-2550 2225);
DISPLAY 0.553191 (-2550 2225);
FORCEPROP 2 LAST TOLERANCE 20%
J 2
(-2475 2275);
DISPLAY 0.553191 (-2475 2275);
DISPLAY INVISIBLE (-2475 2275);
FORCEPROP 2 LAST PACK_TYPE C0201
J 2
(-2575 2275);
DISPLAY 0.553191 (-2575 2275);
DISPLAY INVISIBLE (-2575 2275);
FORCEPROP 1 LAST MATERIAL X6S
J 2
(-2391 2304);
DISPLAY 0.574468 (-2391 2304);
PAINT GREEN (-2391 2304);
DISPLAY INVISIBLE (-2391 2304);
FORCEPROP 2 LAST VOLTAGE 6.3V
J 2
(-2750 2275);
DISPLAY 0.553191 (-2750 2275);
DISPLAY INVISIBLE (-2750 2275);
FORCEPROP 1 LAST PIN_NAMES_ROTATE TRUE
J 2
(-2400 2225);
DISPLAY 0.489362 (-2400 2225);
PAINT GREEN (-2400 2225);
DISPLAY INVISIBLE (-2400 2225);
FORCEPROP 2 LAST CDS_LIB pure_quanta
J 2
(-2400 2225);
DISPLAY INVISIBLE (-2400 2225);
FORCEPROP 1 LAST CDS_LMAN_SYM_OUTLINE -25,50,25,-50
J 2
(-2400 2225);
DISPLAY 0.468085 (-2400 2225);
PAINT GREEN (-2400 2225);
DISPLAY INVISIBLE (-2400 2225);
FORCEPROP 1 LAST PATH I78
J 2
(-2400 2225);
DISPLAY 0.723404 (-2400 2225);
DISPLAY INVISIBLE (-2400 2225);
FORCEPROP 1 LAST PART_NUMBER SP_CH4221MEE01
J 2
(-2516 2313);
DISPLAY 0.574468 (-2516 2313);
PAINT GREEN (-2516 2313);
DISPLAY INVISIBLE (-2516 2313);
FORCEPROP 1 LAST LOCATION C6502
J 0
(-2150 2300);
DISPLAY 1.021277 (-2150 2300);
DISPLAY INVISIBLE (-2150 2300);
FORCEADD TAP..1
(-1850 1675);
FORCEPROP 3 LASTPIN (-1900 1675) SIG_NAME P5E_CPU0_P0_TX_BUF_C_DP<3>
J 0
(-1890 1685);
DISPLAY 0.659574 (-1890 1685);
PAINT MONO (-1890 1685);
DISPLAY INVISIBLE (-1890 1685);
FORCEPROP 1 LASTPIN (-1900 1675) BN 3
J 0
(-1912 1683);
DISPLAY 0.680851 (-1912 1683);
PAINT GREEN (-1912 1683);
FORCEPROP 2 LAST CDS_LIB standard
J 0
(-1850 1675);
DISPLAY INVISIBLE (-1850 1675);
FORCEPROP 1 LAST BODY_TYPE PLUMBING
J 0
(-1850 1725);
DISPLAY 0.872340 (-1850 1725);
PAINT GREEN (-1850 1725);
DISPLAY INVISIBLE (-1850 1725);
FORCEPROP 1 LAST HDL_TAP TRUE
J 0
(-1525 1550);
DISPLAY 0.872340 (-1525 1550);
DISPLAY INVISIBLE (-1525 1550);
FORCEPROP 1 LAST PATH I79
J 0
(-1852 1675);
DISPLAY 0.872340 (-1852 1675);
PAINT GREEN (-1852 1675);
DISPLAY INVISIBLE (-1852 1675);
FORCEADD TAP..1
(-6875 4200);
FORCEPROP 3 LASTPIN (-6925 4200) SIG_NAME P5E_CPU0_P0_TX_BUF_DN<10>
J 0
(-6915 4210);
DISPLAY 0.659574 (-6915 4210);
PAINT MONO (-6915 4210);
DISPLAY INVISIBLE (-6915 4210);
FORCEPROP 1 LASTPIN (-6925 4200) BN 10
J 0
(-6937 4208);
DISPLAY 0.680851 (-6937 4208);
PAINT GREEN (-6937 4208);
FORCEPROP 2 LAST CDS_LIB standard
J 0
(-6875 4200);
DISPLAY INVISIBLE (-6875 4200);
FORCEPROP 1 LAST BODY_TYPE PLUMBING
J 0
(-6875 4250);
DISPLAY 0.872340 (-6875 4250);
PAINT GREEN (-6875 4250);
DISPLAY INVISIBLE (-6875 4250);
FORCEPROP 1 LAST HDL_TAP TRUE
J 0
(-6550 4075);
DISPLAY 0.872340 (-6550 4075);
DISPLAY INVISIBLE (-6550 4075);
FORCEPROP 1 LAST PATH I8
J 0
(-6877 4200);
DISPLAY 0.872340 (-6877 4200);
PAINT GREEN (-6877 4200);
DISPLAY INVISIBLE (-6877 4200);
FORCEADD TAP..1
(-1850 1875);
FORCEPROP 3 LASTPIN (-1900 1875) SIG_NAME P5E_CPU0_P0_TX_BUF_C_DP<2>
J 0
(-1890 1885);
DISPLAY 0.659574 (-1890 1885);
PAINT MONO (-1890 1885);
DISPLAY INVISIBLE (-1890 1885);
FORCEPROP 1 LASTPIN (-1900 1875) BN 2
J 0
(-1912 1883);
DISPLAY 0.680851 (-1912 1883);
PAINT GREEN (-1912 1883);
FORCEPROP 2 LAST CDS_LIB standard
J 0
(-1850 1875);
DISPLAY INVISIBLE (-1850 1875);
FORCEPROP 1 LAST BODY_TYPE PLUMBING
J 0
(-1850 1925);
DISPLAY 0.872340 (-1850 1925);
PAINT GREEN (-1850 1925);
DISPLAY INVISIBLE (-1850 1925);
FORCEPROP 1 LAST HDL_TAP TRUE
J 0
(-1525 1750);
DISPLAY 0.872340 (-1525 1750);
DISPLAY INVISIBLE (-1525 1750);
FORCEPROP 1 LAST PATH I80
J 0
(-1852 1875);
DISPLAY 0.872340 (-1852 1875);
PAINT GREEN (-1852 1875);
DISPLAY INVISIBLE (-1852 1875);
FORCEADD TAP..1
(-1850 2275);
FORCEPROP 3 LASTPIN (-1900 2275) SIG_NAME P5E_CPU0_P0_TX_BUF_C_DP<0>
J 0
(-1890 2285);
DISPLAY 0.659574 (-1890 2285);
PAINT MONO (-1890 2285);
DISPLAY INVISIBLE (-1890 2285);
FORCEPROP 1 LASTPIN (-1900 2275) BN 0
J 0
(-1912 2283);
DISPLAY 0.680851 (-1912 2283);
PAINT GREEN (-1912 2283);
FORCEPROP 2 LAST CDS_LIB standard
J 0
(-1850 2275);
DISPLAY INVISIBLE (-1850 2275);
FORCEPROP 1 LAST BODY_TYPE PLUMBING
J 0
(-1850 2325);
DISPLAY 0.872340 (-1850 2325);
PAINT GREEN (-1850 2325);
DISPLAY INVISIBLE (-1850 2325);
FORCEPROP 1 LAST HDL_TAP TRUE
J 0
(-1525 2150);
DISPLAY 0.872340 (-1525 2150);
DISPLAY INVISIBLE (-1525 2150);
FORCEPROP 1 LAST PATH I81
J 0
(-1852 2275);
DISPLAY 0.872340 (-1852 2275);
PAINT GREEN (-1852 2275);
DISPLAY INVISIBLE (-1852 2275);
FORCEADD TAP..1
(-1650 825);
FORCEPROP 3 LASTPIN (-1700 825) SIG_NAME P5E_CPU0_P0_TX_BUF_C_DN<7>
J 0
(-1690 835);
DISPLAY 0.659574 (-1690 835);
PAINT MONO (-1690 835);
DISPLAY INVISIBLE (-1690 835);
FORCEPROP 1 LASTPIN (-1700 825) BN 7
J 0
(-1712 833);
DISPLAY 0.680851 (-1712 833);
PAINT GREEN (-1712 833);
FORCEPROP 2 LAST CDS_LIB standard
J 0
(-1650 825);
DISPLAY INVISIBLE (-1650 825);
FORCEPROP 1 LAST BODY_TYPE PLUMBING
J 0
(-1650 875);
DISPLAY 0.872340 (-1650 875);
PAINT GREEN (-1650 875);
DISPLAY INVISIBLE (-1650 875);
FORCEPROP 1 LAST HDL_TAP TRUE
J 0
(-1325 700);
DISPLAY 0.872340 (-1325 700);
DISPLAY INVISIBLE (-1325 700);
FORCEPROP 1 LAST PATH I82
J 0
(-1652 825);
DISPLAY 0.872340 (-1652 825);
PAINT GREEN (-1652 825);
DISPLAY INVISIBLE (-1652 825);
FORCEADD TAP..1
(-1650 1025);
FORCEPROP 3 LASTPIN (-1700 1025) SIG_NAME P5E_CPU0_P0_TX_BUF_C_DN<6>
J 0
(-1690 1035);
DISPLAY 0.659574 (-1690 1035);
PAINT MONO (-1690 1035);
DISPLAY INVISIBLE (-1690 1035);
FORCEPROP 1 LASTPIN (-1700 1025) BN 6
J 0
(-1712 1033);
DISPLAY 0.680851 (-1712 1033);
PAINT GREEN (-1712 1033);
FORCEPROP 2 LAST CDS_LIB standard
J 0
(-1650 1025);
DISPLAY INVISIBLE (-1650 1025);
FORCEPROP 1 LAST BODY_TYPE PLUMBING
J 0
(-1650 1075);
DISPLAY 0.872340 (-1650 1075);
PAINT GREEN (-1650 1075);
DISPLAY INVISIBLE (-1650 1075);
FORCEPROP 1 LAST HDL_TAP TRUE
J 0
(-1325 900);
DISPLAY 0.872340 (-1325 900);
DISPLAY INVISIBLE (-1325 900);
FORCEPROP 1 LAST PATH I83
J 0
(-1652 1025);
DISPLAY 0.872340 (-1652 1025);
PAINT GREEN (-1652 1025);
DISPLAY INVISIBLE (-1652 1025);
FORCEADD TAP..1
(-1650 1225);
FORCEPROP 3 LASTPIN (-1700 1225) SIG_NAME P5E_CPU0_P0_TX_BUF_C_DN<5>
J 0
(-1690 1235);
DISPLAY 0.659574 (-1690 1235);
PAINT MONO (-1690 1235);
DISPLAY INVISIBLE (-1690 1235);
FORCEPROP 1 LASTPIN (-1700 1225) BN 5
J 0
(-1712 1233);
DISPLAY 0.680851 (-1712 1233);
PAINT GREEN (-1712 1233);
FORCEPROP 2 LAST CDS_LIB standard
J 0
(-1650 1225);
DISPLAY INVISIBLE (-1650 1225);
FORCEPROP 1 LAST BODY_TYPE PLUMBING
J 0
(-1650 1275);
DISPLAY 0.872340 (-1650 1275);
PAINT GREEN (-1650 1275);
DISPLAY INVISIBLE (-1650 1275);
FORCEPROP 1 LAST HDL_TAP TRUE
J 0
(-1325 1100);
DISPLAY 0.872340 (-1325 1100);
DISPLAY INVISIBLE (-1325 1100);
FORCEPROP 1 LAST PATH I84
J 0
(-1652 1225);
DISPLAY 0.872340 (-1652 1225);
PAINT GREEN (-1652 1225);
DISPLAY INVISIBLE (-1652 1225);
FORCEADD TAP..1
(-1650 1425);
FORCEPROP 3 LASTPIN (-1700 1425) SIG_NAME P5E_CPU0_P0_TX_BUF_C_DN<4>
J 0
(-1690 1435);
DISPLAY 0.659574 (-1690 1435);
PAINT MONO (-1690 1435);
DISPLAY INVISIBLE (-1690 1435);
FORCEPROP 1 LASTPIN (-1700 1425) BN 4
J 0
(-1712 1433);
DISPLAY 0.680851 (-1712 1433);
PAINT GREEN (-1712 1433);
FORCEPROP 2 LAST CDS_LIB standard
J 0
(-1650 1425);
DISPLAY INVISIBLE (-1650 1425);
FORCEPROP 1 LAST BODY_TYPE PLUMBING
J 0
(-1650 1475);
DISPLAY 0.872340 (-1650 1475);
PAINT GREEN (-1650 1475);
DISPLAY INVISIBLE (-1650 1475);
FORCEPROP 1 LAST HDL_TAP TRUE
J 0
(-1325 1300);
DISPLAY 0.872340 (-1325 1300);
DISPLAY INVISIBLE (-1325 1300);
FORCEPROP 1 LAST PATH I85
J 0
(-1652 1425);
DISPLAY 0.872340 (-1652 1425);
PAINT GREEN (-1652 1425);
DISPLAY INVISIBLE (-1652 1425);
FORCEADD TAP..1
(-1650 1625);
FORCEPROP 3 LASTPIN (-1700 1625) SIG_NAME P5E_CPU0_P0_TX_BUF_C_DN<3>
J 0
(-1690 1635);
DISPLAY 0.659574 (-1690 1635);
PAINT MONO (-1690 1635);
DISPLAY INVISIBLE (-1690 1635);
FORCEPROP 1 LASTPIN (-1700 1625) BN 3
J 0
(-1712 1633);
DISPLAY 0.680851 (-1712 1633);
PAINT GREEN (-1712 1633);
FORCEPROP 2 LAST CDS_LIB standard
J 0
(-1650 1625);
DISPLAY INVISIBLE (-1650 1625);
FORCEPROP 1 LAST BODY_TYPE PLUMBING
J 0
(-1650 1675);
DISPLAY 0.872340 (-1650 1675);
PAINT GREEN (-1650 1675);
DISPLAY INVISIBLE (-1650 1675);
FORCEPROP 1 LAST HDL_TAP TRUE
J 0
(-1325 1500);
DISPLAY 0.872340 (-1325 1500);
DISPLAY INVISIBLE (-1325 1500);
FORCEPROP 1 LAST PATH I86
J 0
(-1652 1625);
DISPLAY 0.872340 (-1652 1625);
PAINT GREEN (-1652 1625);
DISPLAY INVISIBLE (-1652 1625);
FORCEADD TAP..1
(-1650 1825);
FORCEPROP 3 LASTPIN (-1700 1825) SIG_NAME P5E_CPU0_P0_TX_BUF_C_DN<2>
J 0
(-1690 1835);
DISPLAY 0.659574 (-1690 1835);
PAINT MONO (-1690 1835);
DISPLAY INVISIBLE (-1690 1835);
FORCEPROP 1 LASTPIN (-1700 1825) BN 2
J 0
(-1712 1833);
DISPLAY 0.680851 (-1712 1833);
PAINT GREEN (-1712 1833);
FORCEPROP 2 LAST CDS_LIB standard
J 0
(-1650 1825);
DISPLAY INVISIBLE (-1650 1825);
FORCEPROP 1 LAST BODY_TYPE PLUMBING
J 0
(-1650 1875);
DISPLAY 0.872340 (-1650 1875);
PAINT GREEN (-1650 1875);
DISPLAY INVISIBLE (-1650 1875);
FORCEPROP 1 LAST HDL_TAP TRUE
J 0
(-1325 1700);
DISPLAY 0.872340 (-1325 1700);
DISPLAY INVISIBLE (-1325 1700);
FORCEPROP 1 LAST PATH I87
J 0
(-1652 1825);
DISPLAY 0.872340 (-1652 1825);
PAINT GREEN (-1652 1825);
DISPLAY INVISIBLE (-1652 1825);
FORCEADD TAP..1
(-1650 2225);
FORCEPROP 3 LASTPIN (-1700 2225) SIG_NAME P5E_CPU0_P0_TX_BUF_C_DN<0>
J 0
(-1690 2235);
DISPLAY 0.659574 (-1690 2235);
PAINT MONO (-1690 2235);
DISPLAY INVISIBLE (-1690 2235);
FORCEPROP 1 LASTPIN (-1700 2225) BN 0
J 0
(-1712 2233);
DISPLAY 0.680851 (-1712 2233);
PAINT GREEN (-1712 2233);
FORCEPROP 2 LAST CDS_LIB standard
J 0
(-1650 2225);
DISPLAY INVISIBLE (-1650 2225);
FORCEPROP 1 LAST BODY_TYPE PLUMBING
J 0
(-1650 2275);
DISPLAY 0.872340 (-1650 2275);
PAINT GREEN (-1650 2275);
DISPLAY INVISIBLE (-1650 2275);
FORCEPROP 1 LAST HDL_TAP TRUE
J 0
(-1325 2100);
DISPLAY 0.872340 (-1325 2100);
DISPLAY INVISIBLE (-1325 2100);
FORCEPROP 1 LAST PATH I88
J 0
(-1652 2225);
DISPLAY 0.872340 (-1652 2225);
PAINT GREEN (-1652 2225);
DISPLAY INVISIBLE (-1652 2225);
FORCEADD OFFPAGE..2
(-650 2300);
FORCEPROP 2 LAST $XR0 118 
J 0
(-461 2300);
DISPLAY 0.638298 (-461 2300);
PAINT MONO (-461 2300);
FORCEPROP 2 LAST CDS_LIB standard
J 0
(-650 2300);
DISPLAY INVISIBLE (-650 2300);
FORCEPROP 1 LAST OFFPAGE TRUE
J 0
(-325 2175);
DISPLAY 0.872340 (-325 2175);
DISPLAY INVISIBLE (-325 2175);
FORCEPROP 1 LAST COMMENT_BODY TRUE
J 0
(-695 2205);
DISPLAY 0.872340 (-695 2205);
PAINT GREEN (-695 2205);
DISPLAY INVISIBLE (-695 2205);
FORCEPROP 2 LAST PATH I89
J 0
(-450 2350);
DISPLAY 0.680851 (-450 2350);
DISPLAY INVISIBLE (-450 2350);
FORCEADD TAP..1
(-6875 4550);
FORCEPROP 3 LASTPIN (-6925 4550) SIG_NAME P5E_CPU0_P0_TX_BUF_DN<11>
J 0
(-6915 4560);
DISPLAY 0.659574 (-6915 4560);
PAINT MONO (-6915 4560);
DISPLAY INVISIBLE (-6915 4560);
FORCEPROP 1 LASTPIN (-6925 4550) BN 11
J 0
(-6937 4558);
DISPLAY 0.680851 (-6937 4558);
PAINT GREEN (-6937 4558);
FORCEPROP 2 LAST CDS_LIB standard
J 0
(-6875 4550);
DISPLAY INVISIBLE (-6875 4550);
FORCEPROP 1 LAST BODY_TYPE PLUMBING
J 0
(-6875 4600);
DISPLAY 0.872340 (-6875 4600);
PAINT GREEN (-6875 4600);
DISPLAY INVISIBLE (-6875 4600);
FORCEPROP 1 LAST HDL_TAP TRUE
J 0
(-6550 4425);
DISPLAY 0.872340 (-6550 4425);
DISPLAY INVISIBLE (-6550 4425);
FORCEPROP 1 LAST PATH I9
J 0
(-6877 4550);
DISPLAY 0.872340 (-6877 4550);
PAINT GREEN (-6877 4550);
DISPLAY INVISIBLE (-6877 4550);
FORCEADD OFFPAGE..2
(-650 2250);
FORCEPROP 2 LAST $XR0 118 
J 0
(-461 2250);
DISPLAY 0.638298 (-461 2250);
PAINT MONO (-461 2250);
FORCEPROP 2 LAST CDS_LIB standard
J 0
(-650 2250);
DISPLAY INVISIBLE (-650 2250);
FORCEPROP 1 LAST OFFPAGE TRUE
J 0
(-325 2125);
DISPLAY 0.872340 (-325 2125);
DISPLAY INVISIBLE (-325 2125);
FORCEPROP 1 LAST COMMENT_BODY TRUE
J 0
(-695 2155);
DISPLAY 0.872340 (-695 2155);
PAINT GREEN (-695 2155);
DISPLAY INVISIBLE (-695 2155);
FORCEPROP 2 LAST PATH I90
J 0
(-450 2300);
DISPLAY 0.680851 (-450 2300);
DISPLAY INVISIBLE (-450 2300);
FORCEADD TAP..1
(-1650 2025);
FORCEPROP 3 LASTPIN (-1700 2025) SIG_NAME P5E_CPU0_P0_TX_BUF_C_DN<1>
J 0
(-1690 2035);
DISPLAY 0.659574 (-1690 2035);
PAINT MONO (-1690 2035);
DISPLAY INVISIBLE (-1690 2035);
FORCEPROP 1 LASTPIN (-1700 2025) BN 1
J 0
(-1712 2033);
DISPLAY 0.680851 (-1712 2033);
PAINT GREEN (-1712 2033);
FORCEPROP 2 LAST CDS_LIB standard
J 0
(-1650 2025);
DISPLAY INVISIBLE (-1650 2025);
FORCEPROP 1 LAST BODY_TYPE PLUMBING
J 0
(-1650 2075);
DISPLAY 0.872340 (-1650 2075);
PAINT GREEN (-1650 2075);
DISPLAY INVISIBLE (-1650 2075);
FORCEPROP 1 LAST HDL_TAP TRUE
J 0
(-1325 1900);
DISPLAY 0.872340 (-1325 1900);
DISPLAY INVISIBLE (-1325 1900);
FORCEPROP 1 LAST PATH I91
J 0
(-1652 2025);
DISPLAY 0.872340 (-1652 2025);
PAINT GREEN (-1652 2025);
DISPLAY INVISIBLE (-1652 2025);
FORCEADD TAP..1
(-1850 2075);
FORCEPROP 3 LASTPIN (-1900 2075) SIG_NAME P5E_CPU0_P0_TX_BUF_C_DP<1>
J 0
(-1890 2085);
DISPLAY 0.659574 (-1890 2085);
PAINT MONO (-1890 2085);
DISPLAY INVISIBLE (-1890 2085);
FORCEPROP 1 LASTPIN (-1900 2075) BN 1
J 0
(-1912 2083);
DISPLAY 0.680851 (-1912 2083);
PAINT GREEN (-1912 2083);
FORCEPROP 2 LAST CDS_LIB standard
J 0
(-1850 2075);
DISPLAY INVISIBLE (-1850 2075);
FORCEPROP 1 LAST BODY_TYPE PLUMBING
J 0
(-1850 2125);
DISPLAY 0.872340 (-1850 2125);
PAINT GREEN (-1850 2125);
DISPLAY INVISIBLE (-1850 2125);
FORCEPROP 1 LAST HDL_TAP TRUE
J 0
(-1525 1950);
DISPLAY 0.872340 (-1525 1950);
DISPLAY INVISIBLE (-1525 1950);
FORCEPROP 1 LAST PATH I92
J 0
(-1852 2075);
DISPLAY 0.872340 (-1852 2075);
PAINT GREEN (-1852 2075);
DISPLAY INVISIBLE (-1852 2075);
FORCEADD OFFPAGE..2
(-5250 2350);
FORCEPROP 2 LAST $XR0 117 
J 0
(-5061 2350);
DISPLAY 0.638298 (-5061 2350);
PAINT MONO (-5061 2350);
FORCEPROP 2 LAST CDS_LIB standard
J 0
(-5250 2350);
DISPLAY INVISIBLE (-5250 2350);
FORCEPROP 1 LAST OFFPAGE TRUE
J 0
(-4925 2225);
DISPLAY 0.872340 (-4925 2225);
DISPLAY INVISIBLE (-4925 2225);
FORCEPROP 1 LAST COMMENT_BODY TRUE
J 0
(-5295 2255);
DISPLAY 0.872340 (-5295 2255);
PAINT GREEN (-5295 2255);
DISPLAY INVISIBLE (-5295 2255);
FORCEPROP 2 LAST PATH I93
J 0
(-5050 2400);
DISPLAY 0.680851 (-5050 2400);
DISPLAY INVISIBLE (-5050 2400);
FORCEADD OFFPAGE..2
(-5250 2300);
FORCEPROP 2 LAST $XR0 117 
J 0
(-5061 2300);
DISPLAY 0.638298 (-5061 2300);
PAINT MONO (-5061 2300);
FORCEPROP 2 LAST CDS_LIB standard
J 0
(-5250 2300);
DISPLAY INVISIBLE (-5250 2300);
FORCEPROP 1 LAST OFFPAGE TRUE
J 0
(-4925 2175);
DISPLAY 0.872340 (-4925 2175);
DISPLAY INVISIBLE (-4925 2175);
FORCEPROP 1 LAST COMMENT_BODY TRUE
J 0
(-5295 2205);
DISPLAY 0.872340 (-5295 2205);
PAINT GREEN (-5295 2205);
DISPLAY INVISIBLE (-5295 2205);
FORCEPROP 2 LAST PATH I94
J 0
(-5050 2350);
DISPLAY 0.680851 (-5050 2350);
DISPLAY INVISIBLE (-5050 2350);
FORCEADD TAP..1
(-6250 2275);
FORCEPROP 3 LASTPIN (-6300 2275) SIG_NAME P5E_CPU0_P0_TX_BUF_C_DN<8>
J 0
(-6290 2285);
DISPLAY 0.659574 (-6290 2285);
PAINT MONO (-6290 2285);
DISPLAY INVISIBLE (-6290 2285);
FORCEPROP 1 LASTPIN (-6300 2275) BN 8
J 0
(-6312 2283);
DISPLAY 0.680851 (-6312 2283);
PAINT GREEN (-6312 2283);
FORCEPROP 2 LAST CDS_LIB standard
J 0
(-6250 2275);
DISPLAY INVISIBLE (-6250 2275);
FORCEPROP 1 LAST BODY_TYPE PLUMBING
J 0
(-6250 2325);
DISPLAY 0.872340 (-6250 2325);
PAINT GREEN (-6250 2325);
DISPLAY INVISIBLE (-6250 2325);
FORCEPROP 1 LAST HDL_TAP TRUE
J 0
(-5925 2150);
DISPLAY 0.872340 (-5925 2150);
DISPLAY INVISIBLE (-5925 2150);
FORCEPROP 1 LAST PATH I95
J 0
(-6252 2275);
DISPLAY 0.872340 (-6252 2275);
PAINT GREEN (-6252 2275);
DISPLAY INVISIBLE (-6252 2275);
FORCEADD TAP..1
(-6250 2075);
FORCEPROP 3 LASTPIN (-6300 2075) SIG_NAME P5E_CPU0_P0_TX_BUF_C_DN<9>
J 0
(-6290 2085);
DISPLAY 0.659574 (-6290 2085);
PAINT MONO (-6290 2085);
DISPLAY INVISIBLE (-6290 2085);
FORCEPROP 1 LASTPIN (-6300 2075) BN 9
J 0
(-6312 2083);
DISPLAY 0.680851 (-6312 2083);
PAINT GREEN (-6312 2083);
FORCEPROP 2 LAST CDS_LIB standard
J 0
(-6250 2075);
DISPLAY INVISIBLE (-6250 2075);
FORCEPROP 1 LAST BODY_TYPE PLUMBING
J 0
(-6250 2125);
DISPLAY 0.872340 (-6250 2125);
PAINT GREEN (-6250 2125);
DISPLAY INVISIBLE (-6250 2125);
FORCEPROP 1 LAST HDL_TAP TRUE
J 0
(-5925 1950);
DISPLAY 0.872340 (-5925 1950);
DISPLAY INVISIBLE (-5925 1950);
FORCEPROP 1 LAST PATH I96
J 0
(-6252 2075);
DISPLAY 0.872340 (-6252 2075);
PAINT GREEN (-6252 2075);
DISPLAY INVISIBLE (-6252 2075);
FORCEADD TAP..1
(-6450 2125);
FORCEPROP 3 LASTPIN (-6500 2125) SIG_NAME P5E_CPU0_P0_TX_BUF_C_DP<9>
J 0
(-6490 2135);
DISPLAY 0.659574 (-6490 2135);
PAINT MONO (-6490 2135);
DISPLAY INVISIBLE (-6490 2135);
FORCEPROP 1 LASTPIN (-6500 2125) BN 9
J 0
(-6512 2133);
DISPLAY 0.680851 (-6512 2133);
PAINT GREEN (-6512 2133);
FORCEPROP 2 LAST CDS_LIB standard
J 0
(-6450 2125);
DISPLAY INVISIBLE (-6450 2125);
FORCEPROP 1 LAST BODY_TYPE PLUMBING
J 0
(-6450 2175);
DISPLAY 0.872340 (-6450 2175);
PAINT GREEN (-6450 2175);
DISPLAY INVISIBLE (-6450 2175);
FORCEPROP 1 LAST HDL_TAP TRUE
J 0
(-6125 2000);
DISPLAY 0.872340 (-6125 2000);
DISPLAY INVISIBLE (-6125 2000);
FORCEPROP 1 LAST PATH I97
J 0
(-6452 2125);
DISPLAY 0.872340 (-6452 2125);
PAINT GREEN (-6452 2125);
DISPLAY INVISIBLE (-6452 2125);
FORCEADD TAP..1
(-6450 2325);
FORCEPROP 3 LASTPIN (-6500 2325) SIG_NAME P5E_CPU0_P0_TX_BUF_C_DP<8>
J 0
(-6490 2335);
DISPLAY 0.659574 (-6490 2335);
PAINT MONO (-6490 2335);
DISPLAY INVISIBLE (-6490 2335);
FORCEPROP 1 LASTPIN (-6500 2325) BN 8
J 0
(-6512 2333);
DISPLAY 0.680851 (-6512 2333);
PAINT GREEN (-6512 2333);
FORCEPROP 2 LAST CDS_LIB standard
J 0
(-6450 2325);
DISPLAY INVISIBLE (-6450 2325);
FORCEPROP 1 LAST BODY_TYPE PLUMBING
J 0
(-6450 2375);
DISPLAY 0.872340 (-6450 2375);
PAINT GREEN (-6450 2375);
DISPLAY INVISIBLE (-6450 2375);
FORCEPROP 1 LAST HDL_TAP TRUE
J 0
(-6125 2200);
DISPLAY 0.872340 (-6125 2200);
DISPLAY INVISIBLE (-6125 2200);
FORCEPROP 1 LAST PATH I98
J 0
(-6452 2325);
DISPLAY 0.872340 (-6452 2325);
PAINT GREEN (-6452 2325);
DISPLAY INVISIBLE (-6452 2325);
FORCEADD Q_CAP_DIFFBUS..2
R 2
(-7000 2325);
FORCEPROP 1 LAST LOCATION C6517
J 2
(-6725 2325);
DISPLAY 0.723404 (-6725 2325);
PAINT GREEN (-6725 2325);
FORCEPROP 2 LAST $SEC 1
J 2
(-6825 2400);
DISPLAY 0.680851 (-6825 2400);
PAINT MONO (-6825 2400);
DISPLAY INVISIBLE (-6825 2400);
FORCEPROP 2 LAST CDS_SEC 1
J 2
(-6825 2400);
DISPLAY 0.680851 (-6825 2400);
DISPLAY INVISIBLE (-6825 2400);
FORCEPROP 2 LASTPIN (-6925 2325) $PN 1
J 0
(-6915 2335);
DISPLAY 0.808511 (-6915 2335);
FORCEPROP 2 LASTPIN (-7075 2325) $PN 2
J 2
(-7085 2335);
DISPLAY 0.808511 (-7085 2335);
FORCEPROP 2 LAST VOLTAGE 6.3V
J 2
(-6825 2475);
DISPLAY 0.553191 (-6825 2475);
PAINT GREEN (-6825 2475);
FORCEPROP 1 LAST MATERIAL X6S
J 2
(-7091 2529);
DISPLAY 0.574468 (-7091 2529);
PAINT GREEN (-7091 2529);
FORCEPROP 2 LAST TOLERANCE 20%
J 2
(-6950 2475);
DISPLAY 0.553191 (-6950 2475);
PAINT GREEN (-6950 2475);
FORCEPROP 2 LAST PACK_TYPE C0201
J 2
(-7050 2475);
DISPLAY 0.553191 (-7050 2475);
PAINT GREEN (-7050 2475);
FORCEPROP 2 LAST VALUE DIFF BUS_0.22UF
J 2
(-7150 2325);
DISPLAY 0.553191 (-7150 2325);
FORCEPROP 2 LAST CDS_LIB pure_quanta
J 2
(-7000 2325);
DISPLAY INVISIBLE (-7000 2325);
FORCEPROP 1 LAST CDS_LMAN_SYM_OUTLINE -25,50,25,-50
J 2
(-7000 2325);
DISPLAY 0.468085 (-7000 2325);
PAINT GREEN (-7000 2325);
DISPLAY INVISIBLE (-7000 2325);
FORCEPROP 1 LAST PIN_NAMES_ROTATE TRUE
J 2
(-7000 2325);
DISPLAY 0.489362 (-7000 2325);
PAINT GREEN (-7000 2325);
DISPLAY INVISIBLE (-7000 2325);
FORCEPROP 1 LAST PATH I99
J 2
(-7000 2325);
DISPLAY 0.723404 (-7000 2325);
DISPLAY INVISIBLE (-7000 2325);
FORCEPROP 1 LAST PART_NUMBER SP_CH4221MEE01
J 2
(-6816 2413);
DISPLAY 0.574468 (-6816 2413);
PAINT GREEN (-6816 2413);
DISPLAY INVISIBLE (-6816 2413);
FORCEPROP 1 LAST LOCATION C6517
J 0
(-6750 2400);
DISPLAY 1.021277 (-6750 2400);
DISPLAY INVISIBLE (-6750 2400);
FORCEADD QUANTA_TITLE_BLOCK_C..1
(0 0);
FORCEPROP 0 LAST CDS_CON_LAST_MODIFIED Thu Sep 14 16:12:49 2023
J 0
(-1885 15);
DISPLAY INVISIBLE (-1885 15);
FORCEPROP 1 LAST CUSTOM_TXT_CDS <CON_LAST_MODIFIED>
J 0
(-1885 15);
DISPLAY 0.978723 (-1885 15);
FORCEPROP 2 LAST CUSTOM_TXT_CDS <XR_PAGE_TITLE>
J 0
(-7890 5250);
DISPLAY 0.638298 (-7890 5250);
PAINT PINK (-7890 5250);
DISPLAY INVISIBLE (-7890 5250);
FORCEPROP 1 LAST CUSTOM_TXT_CDS <NAME_2>
J 0
(-3175 50);
FORCEPROP 1 LAST CUSTOM_TXT_CDS <NAME_1>
J 0
(-3175 175);
FORCEPROP 1 LAST CUSTOM_TXT_CDS <Q_NUMBER>
J 0
(-1403 103);
DISPLAY 1.212766 (-1403 103);
FORCEPROP 1 LAST CUSTOM_TXT_CDS <Q_PROJ>
J 0
(-2382 102);
DISPLAY 1.212766 (-2382 102);
FORCEPROP 1 LAST CUSTOM_TXT_CDS <Q_REV>
J 0
(-184 103);
DISPLAY 1.212766 (-184 103);
FORCEPROP 1 LAST CUSTOM_TXT_CDS <CON_PAGE_NUM> OF <CON_TOTAL_PAGES>
J 0
(-446 18);
DISPLAY 0.978723 (-446 18);
FORCEPROP 1 LAST Q_TITLE RETIMER_CPU0_P0(4)
J 0
(-9366 26);
DISPLAY 2.446809 (-9366 26);
PAINT GREEN (-9366 26);
FORCEPROP 2 LAST PAGE_BORDER TRUE
J 0
(-7890 5250);
DISPLAY 0.638298 (-7890 5250);
PAINT PINK (-7890 5250);
DISPLAY INVISIBLE (-7890 5250);
FORCEPROP 1 LAST CDS_LMAN_SYM_OUTLINE -9475,6775,100,-125
J 0
(0 0);
DISPLAY 0.468085 (0 0);
PAINT GREEN (0 0);
DISPLAY INVISIBLE (0 0);
FORCEPROP 2 LAST CDS_LIB pure_quanta
J 0
(0 0);
DISPLAY INVISIBLE (0 0);
FORCEPROP 2 LAST CDS_XR_PAGE_TITLE CR-276 : @T6G_MB_LIB.T6G(SCH_1):PAGE276
J 0
(-7890 5250);
DISPLAY 0.638298 (-7890 5250);
PAINT PINK (-7890 5250);
DISPLAY INVISIBLE (-7890 5250);
FORCEPROP 1 LAST Q_DEPT BU9
J 1
(-3763 49);
DISPLAY 1.957447 (-3763 49);
PAINT GREEN (-3763 49);
DISPLAY INVISIBLE (-3763 49);
FORCEPROP 1 LAST COMMENT_BODY TRUE
J 0
(12 -13);
DISPLAY 0.978723 (12 -13);
PAINT GREEN (12 -13);
DISPLAY INVISIBLE (12 -13);
WIRE 17 -1 (-3425 850)(-3425 1050);
WIRE 17 -1 (-3425 1050)(-3425 1250);
WIRE 17 -1 (-3425 1250)(-3425 1450);
WIRE 17 -1 (-3425 1450)(-3425 1650);
WIRE 17 -1 (-3425 1650)(-3425 1850);
WIRE 17 -1 (-3425 1850)(-3425 2050);
WIRE 17 -1 (-3425 2050)(-3425 2250);
WIRE 17 -1 (-4275 2250)(-3425 2250);
FORCEPROP 2 LAST SIG_NAME P5E_CPU0_P0_TX_BUF_DN<7:0>
J 0
(-4260 2260);
DISPLAY 0.680851 (-4260 2260);
PAINT WHITE (-4260 2260);
WIRE 17 -1 (-3175 1100)(-3175 900);
WIRE 17 -1 (-3175 1300)(-3175 1100);
WIRE 17 -1 (-3175 1500)(-3175 1300);
WIRE 17 -1 (-3175 1500)(-3175 1700);
WIRE 17 -1 (-3175 1900)(-3175 1700);
WIRE 17 -1 (-3175 2100)(-3175 1900);
WIRE 17 -1 (-3175 2300)(-3175 2100);
WIRE 17 -1 (-4275 2300)(-3175 2300);
FORCEPROP 2 LAST SIG_NAME P5E_CPU0_P0_TX_BUF_DP<7:0>
J 0
(-4260 2310);
DISPLAY 0.680851 (-4260 2310);
PAINT WHITE (-4260 2310);
WIRE 17 -1 (-1800 1100)(-1800 900);
WIRE 17 -1 (-1800 1300)(-1800 1100);
WIRE 17 -1 (-1800 1500)(-1800 1300);
WIRE 17 -1 (-1800 1500)(-1800 1700);
WIRE 17 -1 (-1800 1900)(-1800 1700);
WIRE 17 -1 (-1800 2100)(-1800 1900);
WIRE 17 -1 (-1800 2300)(-1800 2100);
WIRE 17 -1 (-1800 2300)(-700 2300);
FORCEPROP 2 LAST SIG_NAME P5E_CPU0_P0_TX_BUF_C_DP<7:0>
J 0
(-1610 2310);
DISPLAY 0.680851 (-1610 2310);
PAINT WHITE (-1610 2310);
WIRE 17 -1 (-1600 1050)(-1600 850);
WIRE 17 -1 (-1600 1250)(-1600 1050);
WIRE 17 -1 (-1600 1450)(-1600 1250);
WIRE 17 -1 (-1600 1450)(-1600 1650);
WIRE 17 -1 (-1600 1850)(-1600 1650);
WIRE 17 -1 (-1600 2050)(-1600 1850);
WIRE 17 -1 (-1600 2250)(-1600 2050);
FORCEPROP 2 LAST SIG_NAME P5E_CPU0_P0_TX_BUF_C_DN<7:0>
J 0
(-1610 2260);
DISPLAY 0.680851 (-1610 2260);
PAINT WHITE (-1610 2260);
WIRE 17 -1 (-6200 1100)(-6200 900);
WIRE 17 -1 (-6200 1300)(-6200 1100);
WIRE 17 -1 (-6200 1500)(-6200 1300);
WIRE 17 -1 (-6200 1500)(-6200 1700);
WIRE 17 -1 (-6200 1900)(-6200 1700);
WIRE 17 -1 (-6200 2100)(-6200 1900);
WIRE 17 -1 (-6200 2300)(-6200 2100);
FORCEPROP 2 LAST SIG_NAME P5E_CPU0_P0_TX_BUF_C_DN<15:8>
J 0
(-6210 2310);
DISPLAY 0.680851 (-6210 2310);
PAINT WHITE (-6210 2310);
WIRE 17 -1 (-1650 3850)(-1650 3500);
WIRE 17 -1 (-1650 4200)(-1650 3850);
WIRE 17 -1 (-1650 4550)(-1650 4200);
WIRE 17 -1 (-1650 4550)(-1650 4900);
WIRE 17 -1 (-1650 5250)(-1650 4900);
WIRE 17 -1 (-1650 5600)(-1650 5250);
WIRE 17 -1 (-1650 5950)(-1650 5600);
FORCEPROP 2 LAST SIG_NAME P5E_CPU0_P0_TX_BUF_DN<7:0>
J 0
(-1660 5960);
DISPLAY 0.680851 (-1660 5960);
PAINT WHITE (-1660 5960);
WIRE 17 -1 (-1850 4650)(-1850 5000);
WIRE 17 -1 (-1850 4650)(-1850 4300);
WIRE 17 -1 (-1850 5350)(-1850 5000);
WIRE 17 -1 (-1850 5700)(-1850 5350);
WIRE 17 -1 (-1850 4300)(-1850 3950);
WIRE 17 -1 (-1850 3950)(-1850 3600);
WIRE 17 -1 (-1850 6050)(-1850 5700);
WIRE 17 -1 (-1850 6050)(-750 6050);
FORCEPROP 2 LAST SIG_NAME P5E_CPU0_P0_TX_BUF_DP<7:0>
J 0
(-1660 6060);
DISPLAY 0.680851 (-1660 6060);
PAINT WHITE (-1660 6060);
WIRE 17 -1 (-8025 900)(-8025 1100);
WIRE 17 -1 (-8025 1100)(-8025 1300);
WIRE 17 -1 (-8025 1300)(-8025 1500);
WIRE 17 -1 (-8025 1500)(-8025 1700);
WIRE 17 -1 (-8025 1700)(-8025 1900);
WIRE 17 -1 (-8025 1900)(-8025 2100);
WIRE 17 -1 (-8025 2100)(-8025 2300);
WIRE 17 -1 (-8875 2300)(-8025 2300);
FORCEPROP 2 LAST SIG_NAME P5E_CPU0_P0_TX_BUF_DN<15:8>
J 0
(-8860 2310);
DISPLAY 0.680851 (-8860 2310);
PAINT WHITE (-8860 2310);
WIRE 17 -1 (-6825 4575)(-6825 4925);
WIRE 17 -1 (-6825 4575)(-6825 4225);
WIRE 17 -1 (-6825 5275)(-6825 4925);
WIRE 17 -1 (-6825 5625)(-6825 5275);
WIRE 17 -1 (-6825 4225)(-6825 3875);
WIRE 17 -1 (-6825 3875)(-6825 3525);
WIRE 17 -1 (-6825 5975)(-6825 5625);
FORCEPROP 2 LAST SIG_NAME P5E_CPU0_P0_TX_BUF_DN<15:8>
J 0
(-6835 5985);
DISPLAY 0.680851 (-6835 5985);
PAINT WHITE (-6835 5985);
WIRE 17 -1 (-7775 1150)(-7775 950);
WIRE 17 -1 (-7775 1350)(-7775 1150);
WIRE 17 -1 (-7775 1550)(-7775 1350);
WIRE 17 -1 (-7775 1550)(-7775 1750);
WIRE 17 -1 (-7775 1950)(-7775 1750);
WIRE 17 -1 (-7775 2150)(-7775 1950);
WIRE 17 -1 (-7775 2350)(-7775 2150);
WIRE 17 -1 (-8875 2350)(-7775 2350);
FORCEPROP 2 LAST SIG_NAME P5E_CPU0_P0_TX_BUF_DP<15:8>
J 0
(-8860 2360);
DISPLAY 0.680851 (-8860 2360);
PAINT WHITE (-8860 2360);
WIRE 17 -1 (-7025 6075)(-7025 5725);
WIRE 17 -1 (-7025 6075)(-5925 6075);
FORCEPROP 2 LAST SIG_NAME P5E_CPU0_P0_TX_BUF_DP<15:8>
J 0
(-6835 6085);
DISPLAY 0.680851 (-6835 6085);
PAINT WHITE (-6835 6085);
WIRE 17 -1 (-7025 4675)(-7025 5025);
WIRE 17 -1 (-7025 4675)(-7025 4325);
WIRE 17 -1 (-7025 5375)(-7025 5025);
WIRE 17 -1 (-7025 5725)(-7025 5375);
WIRE 17 -1 (-7025 4325)(-7025 3975);
WIRE 17 -1 (-7025 3975)(-7025 3625);
WIRE 17 -1 (-6400 2350)(-6400 2150);
WIRE 17 -1 (-6400 2350)(-5300 2350);
FORCEPROP 2 LAST SIG_NAME P5E_CPU0_P0_TX_BUF_C_DP<15:8>
J 0
(-6210 2360);
DISPLAY 0.680851 (-6210 2360);
PAINT WHITE (-6210 2360);
WIRE 17 -1 (-6400 1150)(-6400 950);
WIRE 17 -1 (-6400 1350)(-6400 1150);
WIRE 17 -1 (-6400 1550)(-6400 1350);
WIRE 17 -1 (-6400 1550)(-6400 1750);
WIRE 17 -1 (-6400 1950)(-6400 1750);
WIRE 17 -1 (-6400 2150)(-6400 1950);
WIRE 17 -1 (-1600 2250)(-700 2250);
WIRE 17 -1 (-6200 2300)(-5300 2300);
WIRE 17 -1 (-1650 5950)(-775 5950);
WIRE 17 -1 (-6825 5975)(-5950 5975);
WIRE 16 -1 (-7350 5250)(-6925 5250);
WIRE 16 -1 (-7350 4550)(-6925 4550);
WIRE 16 -1 (-7350 4200)(-6925 4200);
WIRE 16 -1 (-7350 3850)(-6925 3850);
WIRE 16 -1 (-7350 3500)(-6925 3500);
WIRE 16 -1 (-7075 2325)(-7675 2325);
WIRE 16 -1 (-7075 2275)(-7925 2275);
WIRE 16 -1 (-6925 2075)(-6300 2075);
WIRE 16 -1 (-7075 1875)(-7925 1875);
WIRE 16 -1 (-6925 1925)(-6500 1925);
WIRE 16 -1 (-6925 2325)(-6500 2325);
WIRE 16 -1 (-6925 1725)(-6500 1725);
WIRE 16 -1 (-6925 1525)(-6500 1525);
WIRE 16 -1 (-6925 1325)(-6500 1325);
WIRE 16 -1 (-6925 1125)(-6500 1125);
WIRE 16 -1 (-6925 925)(-6500 925);
WIRE 16 -1 (-6925 2125)(-6500 2125);
WIRE 16 -1 (-7350 5350)(-7125 5350);
WIRE 16 -1 (-7350 6050)(-7125 6050);
WIRE 16 -1 (-7350 5950)(-6925 5950);
WIRE 16 -1 (-7350 5600)(-6925 5600);
WIRE 16 -1 (-7075 2125)(-7675 2125);
WIRE 16 -1 (-7075 1925)(-7675 1925);
WIRE 16 -1 (-7075 1275)(-7925 1275);
WIRE 16 -1 (-7075 1475)(-7925 1475);
WIRE 16 -1 (-7075 1675)(-7925 1675);
WIRE 16 -1 (-6925 2275)(-6300 2275);
WIRE 16 -1 (-7075 2075)(-7925 2075);
WIRE 16 -1 (-7350 3600)(-7125 3600);
WIRE 16 -1 (-7350 3950)(-7125 3950);
WIRE 16 -1 (-7350 4300)(-7125 4300);
WIRE 16 -1 (-7350 5000)(-7125 5000);
WIRE 16 -1 (-7075 1525)(-7675 1525);
WIRE 16 -1 (-7350 4650)(-7125 4650);
WIRE 16 -1 (-7075 1725)(-7675 1725);
WIRE 16 -1 (-7075 1325)(-7675 1325);
WIRE 16 -1 (-7350 5700)(-7125 5700);
WIRE 16 -1 (-7075 1125)(-7675 1125);
WIRE 16 -1 (-7075 925)(-7675 925);
WIRE 16 -1 (-7350 4900)(-6925 4900);
WIRE 16 -1 (-6925 1675)(-6300 1675);
WIRE 16 -1 (-6925 1475)(-6300 1475);
WIRE 16 -1 (-6925 1275)(-6300 1275);
WIRE 16 -1 (-7075 1075)(-7925 1075);
WIRE 16 -1 (-7075 875)(-7925 875);
WIRE 16 -1 (-6925 1875)(-6300 1875);
WIRE 16 -1 (-2175 5925)(-1750 5925);
WIRE 16 -1 (-2175 6025)(-1950 6025);
WIRE 16 -1 (-2175 5675)(-1950 5675);
WIRE 16 -1 (-2175 5575)(-1750 5575);
WIRE 16 -1 (-2175 5225)(-1750 5225);
WIRE 16 -1 (-2175 4975)(-1950 4975);
WIRE 16 -1 (-2175 4175)(-1750 4175);
WIRE 16 -1 (-2175 4275)(-1950 4275);
WIRE 16 -1 (-2175 3925)(-1950 3925);
WIRE 16 -1 (-2175 3575)(-1950 3575);
WIRE 16 -1 (-2175 5325)(-1950 5325);
WIRE 16 -1 (-2175 3825)(-1750 3825);
WIRE 16 -1 (-2175 4525)(-1750 4525);
WIRE 16 -1 (-2175 4625)(-1950 4625);
WIRE 16 -1 (-2175 4875)(-1750 4875);
WIRE 16 -1 (-2175 3475)(-1750 3475);
WIRE 16 -1 (-6925 1075)(-6300 1075);
WIRE 16 -1 (-6925 875)(-6300 875);
WIRE 16 -1 (-2325 1425)(-1700 1425);
WIRE 16 -1 (-2325 1475)(-1900 1475);
WIRE 16 -1 (-2325 2275)(-1900 2275);
WIRE 16 -1 (-2325 2225)(-1700 2225);
WIRE 16 -1 (-2325 2075)(-1900 2075);
WIRE 16 -1 (-2325 2025)(-1700 2025);
WIRE 16 -1 (-2325 1875)(-1900 1875);
WIRE 16 -1 (-2325 1825)(-1700 1825);
WIRE 16 -1 (-2325 1625)(-1700 1625);
WIRE 16 -1 (-2325 1675)(-1900 1675);
WIRE 16 -1 (-2325 1275)(-1900 1275);
WIRE 16 -1 (-2325 1225)(-1700 1225);
WIRE 16 -1 (-2325 1075)(-1900 1075);
WIRE 16 -1 (-2325 1025)(-1700 1025);
WIRE 16 -1 (-2325 825)(-1700 825);
WIRE 16 -1 (-2325 875)(-1900 875);
WIRE 16 -1 (-2475 2275)(-3075 2275);
WIRE 16 -1 (-2475 2075)(-3075 2075);
WIRE 16 -1 (-2475 1875)(-3075 1875);
WIRE 16 -1 (-2475 2225)(-3325 2225);
WIRE 16 -1 (-2475 1825)(-3325 1825);
WIRE 16 -1 (-2475 2025)(-3325 2025);
WIRE 16 -1 (-2475 1675)(-3075 1675);
WIRE 16 -1 (-2475 1475)(-3075 1475);
WIRE 16 -1 (-2475 1625)(-3325 1625);
WIRE 16 -1 (-2475 1425)(-3325 1425);
WIRE 16 -1 (-2475 1275)(-3075 1275);
WIRE 16 -1 (-2475 1075)(-3075 1075);
WIRE 16 -1 (-2475 875)(-3075 875);
WIRE 16 -1 (-2475 1225)(-3325 1225);
WIRE 16 -1 (-2475 1025)(-3325 1025);
WIRE 16 -1 (-2475 825)(-3325 825);
FORCENOTE
P5E_CPU0_P0_TX_BUF_DP/DN<0-15> LANE REVERSAL
(-7325 6375) 0;
DISPLAY LEFT (-7325 6375);
DISPLAY 2.000000 (-7325 6375);
FORCENOTE
RETIMER TO EXAMAX
(-3700 3125) 0;
DISPLAY LEFT (-3700 3125);
DISPLAY 3.148936 (-3700 3125);
FORCENOTE
RETIMER TO EXAMAX
(-8700 3150) 0;
DISPLAY LEFT (-8700 3150);
DISPLAY 3.148936 (-8700 3150);
QUIT
